FILE_TYPE = MACRO_DRAWING;
SET COLOR_WIRE YELLOW;
SET COLOR_PROP ORANGE;
SET COLOR_DOT WHITE;
SET COLOR_ARC YELLOW;
SET COLOR_BODY GREEN;
SET COLOR_NOTE PURPLE;
SET PROP_DISPLAY VALUE;
SET PAGE_NUMBER P108;
FORCEADD OFFPAGE..2
R 2
(-3650 1400);
FORCEPROP 2 LAST $XR0 108 
J 0
(-3905 1400);
DISPLAY 0.638298 (-3905 1400);
PAINT MONO (-3905 1400);
FORCEPROP 2 LAST CDS_LIB standard
J 0
(-3650 1400);
PAINT MONO (-3650 1400);
DISPLAY INVISIBLE (-3650 1400);
FORCEPROP 1 LAST OFFPAGE TRUE
J 2
(-3975 1275);
DISPLAY 0.872340 (-3975 1275);
DISPLAY INVISIBLE (-3975 1275);
FORCEPROP 1 LAST COMMENT_BODY TRUE
J 2
(-3605 1305);
DISPLAY 0.872340 (-3605 1305);
PAINT GREEN (-3605 1305);
DISPLAY INVISIBLE (-3605 1305);
FORCEPROP 2 LAST PATH I1
J 0
(-3600 1475);
DISPLAY 1.021277 (-3600 1475);
DISPLAY INVISIBLE (-3600 1475);
FORCEADD Q_RES..2
(-2500 1200);
FORCEPROP 1 LAST PART_NUMBER CS32322FB03
J 0
(-2460 1075);
DISPLAY 0.978723 (-2460 1075);
DISPLAY INVISIBLE (-2460 1075);
FORCEPROP 1 LAST VALUE 23.2K
J 0
(-2455 1275);
DISPLAY 0.978723 (-2455 1275);
FORCEPROP 1 LAST WATTAGE 1/16W
J 0
(-2460 1175);
DISPLAY 0.978723 (-2460 1175);
FORCEPROP 1 LAST MATERIAL CHIP
J 0
(-2460 1125);
DISPLAY 0.978723 (-2460 1125);
FORCEPROP 1 LAST PACK_TYPE 0402LF
J 0
(-2460 1025);
DISPLAY 0.978723 (-2460 1025);
FORCEPROP 1 LAST TOLERANCE 1%
J 0
(-2455 1225);
DISPLAY 0.978723 (-2455 1225);
FORCEPROP 1 LAST $LOCATION R77
J 0
(-2455 1325);
DISPLAY 0.978723 (-2455 1325);
FORCEPROP 1 LASTPIN (-2500 1300) $PN 1
J 0
(-2495 1262);
DISPLAY 0.787234 (-2495 1262);
FORCEPROP 1 LASTPIN (-2500 1100) $PN 2
J 0
(-2495 1110);
DISPLAY 0.787234 (-2495 1110);
FORCEPROP 2 LAST CDS_LIB pure_quanta
J 0
(-2500 1200);
PAINT MONO (-2500 1200);
DISPLAY INVISIBLE (-2500 1200);
FORCEPROP 1 LAST PATH I10
J 0
(-2450 1375);
DISPLAY 0.978723 (-2450 1375);
PAINT WHITE (-2450 1375);
DISPLAY INVISIBLE (-2450 1375);
FORCEPROP 1 LAST $LOCATION R77
J 0
(-2450 1425);
DISPLAY 1.021277 (-2450 1425);
DISPLAY INVISIBLE (-2450 1425);
FORCEPROP 2 LAST CDS_LOCATION R77
J 0
(-2450 1425);
DISPLAY 1.021277 (-2450 1425);
DISPLAY INVISIBLE (-2450 1425);
FORCEPROP 2 LAST $SEC 1
J 0
(-2450 1425);
DISPLAY 0.680851 (-2450 1425);
PAINT MONO (-2450 1425);
DISPLAY INVISIBLE (-2450 1425);
FORCEPROP 2 LAST CDS_SEC 1
J 0
(-2450 1425);
DISPLAY 1.021277 (-2450 1425);
DISPLAY INVISIBLE (-2450 1425);
FORCEADD TAP..1
(-1075 4900);
FORCEPROP 3 LASTPIN (-1125 4900) SIG_NAME M_F_CPU1_SA_DQ<22>
J 0
(-1115 4910);
DISPLAY 0.659574 (-1115 4910);
PAINT MONO (-1115 4910);
DISPLAY INVISIBLE (-1115 4910);
FORCEPROP 1 LASTPIN (-1125 4900) BN 22
J 0
(-1137 4908);
DISPLAY 0.680851 (-1137 4908);
PAINT GREEN (-1137 4908);
FORCEPROP 2 LAST CDS_LIB standard
J 0
(-1075 4900);
DISPLAY INVISIBLE (-1075 4900);
FORCEPROP 1 LAST BODY_TYPE PLUMBING
J 0
(-1075 4950);
DISPLAY 0.872340 (-1075 4950);
PAINT GREEN (-1075 4950);
DISPLAY INVISIBLE (-1075 4950);
FORCEPROP 1 LAST HDL_TAP TRUE
J 0
(-750 4775);
DISPLAY 0.872340 (-750 4775);
DISPLAY INVISIBLE (-750 4775);
FORCEPROP 1 LAST PATH I100
J 0
(-1077 4900);
DISPLAY 0.872340 (-1077 4900);
PAINT GREEN (-1077 4900);
DISPLAY INVISIBLE (-1077 4900);
FORCEADD TAP..1
(-1075 5000);
FORCEPROP 3 LASTPIN (-1125 5000) SIG_NAME M_F_CPU1_SA_DQ<24>
J 0
(-1115 5010);
DISPLAY 0.659574 (-1115 5010);
PAINT MONO (-1115 5010);
DISPLAY INVISIBLE (-1115 5010);
FORCEPROP 1 LASTPIN (-1125 5000) BN 24
J 0
(-1137 5008);
DISPLAY 0.680851 (-1137 5008);
PAINT GREEN (-1137 5008);
FORCEPROP 2 LAST CDS_LIB standard
J 0
(-1075 5000);
DISPLAY INVISIBLE (-1075 5000);
FORCEPROP 1 LAST BODY_TYPE PLUMBING
J 0
(-1075 5050);
DISPLAY 0.872340 (-1075 5050);
PAINT GREEN (-1075 5050);
DISPLAY INVISIBLE (-1075 5050);
FORCEPROP 1 LAST HDL_TAP TRUE
J 0
(-750 4875);
DISPLAY 0.872340 (-750 4875);
DISPLAY INVISIBLE (-750 4875);
FORCEPROP 1 LAST PATH I101
J 0
(-1077 5000);
DISPLAY 0.872340 (-1077 5000);
PAINT GREEN (-1077 5000);
DISPLAY INVISIBLE (-1077 5000);
FORCEADD TAP..1
(-1075 4950);
FORCEPROP 3 LASTPIN (-1125 4950) SIG_NAME M_F_CPU1_SA_DQ<23>
J 0
(-1115 4960);
DISPLAY 0.659574 (-1115 4960);
PAINT MONO (-1115 4960);
DISPLAY INVISIBLE (-1115 4960);
FORCEPROP 1 LASTPIN (-1125 4950) BN 23
J 0
(-1137 4958);
DISPLAY 0.680851 (-1137 4958);
PAINT GREEN (-1137 4958);
FORCEPROP 2 LAST CDS_LIB standard
J 0
(-1075 4950);
DISPLAY INVISIBLE (-1075 4950);
FORCEPROP 1 LAST BODY_TYPE PLUMBING
J 0
(-1075 5000);
DISPLAY 0.872340 (-1075 5000);
PAINT GREEN (-1075 5000);
DISPLAY INVISIBLE (-1075 5000);
FORCEPROP 1 LAST HDL_TAP TRUE
J 0
(-750 4825);
DISPLAY 0.872340 (-750 4825);
DISPLAY INVISIBLE (-750 4825);
FORCEPROP 1 LAST PATH I102
J 0
(-1077 4950);
DISPLAY 0.872340 (-1077 4950);
PAINT GREEN (-1077 4950);
DISPLAY INVISIBLE (-1077 4950);
FORCEADD OFFPAGE..3
(-250 3725);
FORCEPROP 2 LAST $XR1 109 
J 0
(54 3725);
DISPLAY 0.638298 (54 3725);
PAINT MONO (54 3725);
FORCEPROP 2 LAST $XR0 56 
J 0
(-36 3725);
DISPLAY 0.638298 (-36 3725);
PAINT MONO (-36 3725);
FORCEPROP 2 LAST CDS_LIB standard
J 2
(-250 3725);
DISPLAY INVISIBLE (-250 3725);
FORCEPROP 1 LAST OFFPAGE TRUE
J 0
(75 3600);
DISPLAY 0.872340 (75 3600);
DISPLAY INVISIBLE (75 3600);
FORCEPROP 1 LAST COMMENT_BODY TRUE
J 0
(-300 3625);
DISPLAY 0.872340 (-300 3625);
PAINT GREEN (-300 3625);
DISPLAY INVISIBLE (-300 3625);
FORCEPROP 2 LAST PATH I103
J 0
(-50 3800);
DISPLAY 1.021277 (-50 3800);
DISPLAY INVISIBLE (-50 3800);
FORCEADD OFFPAGE..1
(-3650 5375);
FORCEPROP 2 LAST $XR1 109 
J 0
(-3991 5375);
DISPLAY 0.638298 (-3991 5375);
PAINT MONO (-3991 5375);
FORCEPROP 2 LAST $XR0 56 
J 0
(-3871 5375);
DISPLAY 0.638298 (-3871 5375);
PAINT MONO (-3871 5375);
FORCEPROP 2 LAST CDS_LIB standard
J 0
(-3650 5375);
PAINT MONO (-3650 5375);
DISPLAY INVISIBLE (-3650 5375);
FORCEPROP 1 LAST OFFPAGE TRUE
J 0
(-3325 5250);
DISPLAY 0.872340 (-3325 5250);
DISPLAY INVISIBLE (-3325 5250);
FORCEPROP 1 LAST COMMENT_BODY TRUE
J 0
(-3525 5275);
DISPLAY 0.872340 (-3525 5275);
PAINT GREEN (-3525 5275);
DISPLAY INVISIBLE (-3525 5275);
FORCEPROP 2 LAST PATH I104
J 0
(-3600 5450);
DISPLAY 1.021277 (-3600 5450);
DISPLAY INVISIBLE (-3600 5450);
FORCEADD TAP..1
R 2
(-2725 5100);
FORCEPROP 3 LASTPIN (-2675 5100) SIG_NAME M_F_CPU1_SA_CA<1>
J 0
(-2665 5110);
DISPLAY 0.659574 (-2665 5110);
PAINT MONO (-2665 5110);
DISPLAY INVISIBLE (-2665 5110);
FORCEPROP 1 LASTPIN (-2675 5100) BN 1
J 2
(-2663 5108);
DISPLAY 0.680851 (-2663 5108);
PAINT GREEN (-2663 5108);
FORCEPROP 2 LAST CDS_LIB standard
J 0
(-2725 5100);
DISPLAY INVISIBLE (-2725 5100);
FORCEPROP 1 LAST BODY_TYPE PLUMBING
J 2
(-2725 5150);
DISPLAY 0.872340 (-2725 5150);
PAINT GREEN (-2725 5150);
DISPLAY INVISIBLE (-2725 5150);
FORCEPROP 1 LAST HDL_TAP TRUE
J 2
(-3050 4975);
DISPLAY 0.872340 (-3050 4975);
DISPLAY INVISIBLE (-3050 4975);
FORCEPROP 1 LAST PATH I105
J 2
(-2723 5100);
DISPLAY 0.872340 (-2723 5100);
PAINT GREEN (-2723 5100);
DISPLAY INVISIBLE (-2723 5100);
FORCEADD TAP..1
R 2
(-2725 5050);
FORCEPROP 3 LASTPIN (-2675 5050) SIG_NAME M_F_CPU1_SA_CA<0>
J 0
(-2665 5060);
DISPLAY 0.659574 (-2665 5060);
PAINT MONO (-2665 5060);
DISPLAY INVISIBLE (-2665 5060);
FORCEPROP 1 LASTPIN (-2675 5050) BN 0
J 2
(-2663 5058);
DISPLAY 0.680851 (-2663 5058);
PAINT GREEN (-2663 5058);
FORCEPROP 2 LAST CDS_LIB standard
J 0
(-2725 5050);
DISPLAY INVISIBLE (-2725 5050);
FORCEPROP 1 LAST BODY_TYPE PLUMBING
J 2
(-2725 5100);
DISPLAY 0.872340 (-2725 5100);
PAINT GREEN (-2725 5100);
DISPLAY INVISIBLE (-2725 5100);
FORCEPROP 1 LAST HDL_TAP TRUE
J 2
(-3050 4925);
DISPLAY 0.872340 (-3050 4925);
DISPLAY INVISIBLE (-3050 4925);
FORCEPROP 1 LAST PATH I106
J 2
(-2723 5050);
DISPLAY 0.872340 (-2723 5050);
PAINT GREEN (-2723 5050);
DISPLAY INVISIBLE (-2723 5050);
FORCEADD TAP..1
R 2
(-2725 5150);
FORCEPROP 3 LASTPIN (-2675 5150) SIG_NAME M_F_CPU1_SA_CA<2>
J 0
(-2665 5160);
DISPLAY 0.659574 (-2665 5160);
PAINT MONO (-2665 5160);
DISPLAY INVISIBLE (-2665 5160);
FORCEPROP 1 LASTPIN (-2675 5150) BN 2
J 2
(-2663 5158);
DISPLAY 0.680851 (-2663 5158);
PAINT GREEN (-2663 5158);
FORCEPROP 2 LAST CDS_LIB standard
J 0
(-2725 5150);
DISPLAY INVISIBLE (-2725 5150);
FORCEPROP 1 LAST BODY_TYPE PLUMBING
J 2
(-2725 5200);
DISPLAY 0.872340 (-2725 5200);
PAINT GREEN (-2725 5200);
DISPLAY INVISIBLE (-2725 5200);
FORCEPROP 1 LAST HDL_TAP TRUE
J 2
(-3050 5025);
DISPLAY 0.872340 (-3050 5025);
DISPLAY INVISIBLE (-3050 5025);
FORCEPROP 1 LAST PATH I107
J 2
(-2723 5150);
DISPLAY 0.872340 (-2723 5150);
PAINT GREEN (-2723 5150);
DISPLAY INVISIBLE (-2723 5150);
FORCEADD TAP..1
R 2
(-2725 5200);
FORCEPROP 3 LASTPIN (-2675 5200) SIG_NAME M_F_CPU1_SA_CA<3>
J 0
(-2665 5210);
DISPLAY 0.659574 (-2665 5210);
PAINT MONO (-2665 5210);
DISPLAY INVISIBLE (-2665 5210);
FORCEPROP 1 LASTPIN (-2675 5200) BN 3
J 2
(-2663 5208);
DISPLAY 0.680851 (-2663 5208);
PAINT GREEN (-2663 5208);
FORCEPROP 2 LAST CDS_LIB standard
J 0
(-2725 5200);
DISPLAY INVISIBLE (-2725 5200);
FORCEPROP 1 LAST BODY_TYPE PLUMBING
J 2
(-2725 5250);
DISPLAY 0.872340 (-2725 5250);
PAINT GREEN (-2725 5250);
DISPLAY INVISIBLE (-2725 5250);
FORCEPROP 1 LAST HDL_TAP TRUE
J 2
(-3050 5075);
DISPLAY 0.872340 (-3050 5075);
DISPLAY INVISIBLE (-3050 5075);
FORCEPROP 1 LAST PATH I108
J 2
(-2723 5200);
DISPLAY 0.872340 (-2723 5200);
PAINT GREEN (-2723 5200);
DISPLAY INVISIBLE (-2723 5200);
FORCEADD TAP..1
R 2
(-2725 5250);
FORCEPROP 3 LASTPIN (-2675 5250) SIG_NAME M_F_CPU1_SA_CA<4>
J 0
(-2665 5260);
DISPLAY 0.659574 (-2665 5260);
PAINT MONO (-2665 5260);
DISPLAY INVISIBLE (-2665 5260);
FORCEPROP 1 LASTPIN (-2675 5250) BN 4
J 2
(-2663 5258);
DISPLAY 0.680851 (-2663 5258);
PAINT GREEN (-2663 5258);
FORCEPROP 2 LAST CDS_LIB standard
J 0
(-2725 5250);
DISPLAY INVISIBLE (-2725 5250);
FORCEPROP 1 LAST BODY_TYPE PLUMBING
J 2
(-2725 5300);
DISPLAY 0.872340 (-2725 5300);
PAINT GREEN (-2725 5300);
DISPLAY INVISIBLE (-2725 5300);
FORCEPROP 1 LAST HDL_TAP TRUE
J 2
(-3050 5125);
DISPLAY 0.872340 (-3050 5125);
DISPLAY INVISIBLE (-3050 5125);
FORCEPROP 1 LAST PATH I109
J 2
(-2723 5250);
DISPLAY 0.872340 (-2723 5250);
PAINT GREEN (-2723 5250);
DISPLAY INVISIBLE (-2723 5250);
FORCEADD OFFPAGE..1
(-3650 3100);
FORCEPROP 2 LAST $XR3 109 
J 0
(-4022 3064);
DISPLAY 0.638298 (-4022 3064);
PAINT MONO (-4022 3064);
FORCEPROP 2 LAST $XR2 107 
J 0
(-3902 3064);
DISPLAY 0.638298 (-3902 3064);
PAINT MONO (-3902 3064);
FORCEPROP 2 LAST $XR1 106 
J 0
(-4022 3100);
DISPLAY 0.638298 (-4022 3100);
PAINT MONO (-4022 3100);
FORCEPROP 2 LAST $XR0 130 
J 0
(-3902 3100);
DISPLAY 0.638298 (-3902 3100);
PAINT MONO (-3902 3100);
FORCEPROP 2 LAST CDS_LIB standard
J 0
(-3650 3100);
PAINT MONO (-3650 3100);
DISPLAY INVISIBLE (-3650 3100);
FORCEPROP 1 LAST OFFPAGE TRUE
J 0
(-3325 2975);
DISPLAY 0.872340 (-3325 2975);
DISPLAY INVISIBLE (-3325 2975);
FORCEPROP 1 LAST COMMENT_BODY TRUE
J 0
(-3525 3000);
DISPLAY 0.872340 (-3525 3000);
PAINT GREEN (-3525 3000);
DISPLAY INVISIBLE (-3525 3000);
FORCEPROP 2 LAST PATH I11
J 0
(-3600 3175);
DISPLAY 1.021277 (-3600 3175);
DISPLAY INVISIBLE (-3600 3175);
FORCEADD TAP..1
R 2
(-2725 5300);
FORCEPROP 3 LASTPIN (-2675 5300) SIG_NAME M_F_CPU1_SA_CA<5>
J 0
(-2665 5310);
DISPLAY 0.659574 (-2665 5310);
PAINT MONO (-2665 5310);
DISPLAY INVISIBLE (-2665 5310);
FORCEPROP 1 LASTPIN (-2675 5300) BN 5
J 2
(-2663 5308);
DISPLAY 0.680851 (-2663 5308);
PAINT GREEN (-2663 5308);
FORCEPROP 2 LAST CDS_LIB standard
J 0
(-2725 5300);
DISPLAY INVISIBLE (-2725 5300);
FORCEPROP 1 LAST BODY_TYPE PLUMBING
J 2
(-2725 5350);
DISPLAY 0.872340 (-2725 5350);
PAINT GREEN (-2725 5350);
DISPLAY INVISIBLE (-2725 5350);
FORCEPROP 1 LAST HDL_TAP TRUE
J 2
(-3050 5175);
DISPLAY 0.872340 (-3050 5175);
DISPLAY INVISIBLE (-3050 5175);
FORCEPROP 1 LAST PATH I110
J 2
(-2723 5300);
DISPLAY 0.872340 (-2723 5300);
PAINT GREEN (-2723 5300);
DISPLAY INVISIBLE (-2723 5300);
FORCEADD TAP..1
R 2
(-2725 5350);
FORCEPROP 3 LASTPIN (-2675 5350) SIG_NAME M_F_CPU1_SA_CA<6>
J 0
(-2665 5360);
DISPLAY 0.659574 (-2665 5360);
PAINT MONO (-2665 5360);
DISPLAY INVISIBLE (-2665 5360);
FORCEPROP 1 LASTPIN (-2675 5350) BN 6
J 2
(-2663 5358);
DISPLAY 0.680851 (-2663 5358);
PAINT GREEN (-2663 5358);
FORCEPROP 2 LAST CDS_LIB standard
J 0
(-2725 5350);
DISPLAY INVISIBLE (-2725 5350);
FORCEPROP 1 LAST BODY_TYPE PLUMBING
J 2
(-2725 5400);
DISPLAY 0.872340 (-2725 5400);
PAINT GREEN (-2725 5400);
DISPLAY INVISIBLE (-2725 5400);
FORCEPROP 1 LAST HDL_TAP TRUE
J 2
(-3050 5225);
DISPLAY 0.872340 (-3050 5225);
DISPLAY INVISIBLE (-3050 5225);
FORCEPROP 1 LAST PATH I111
J 2
(-2723 5350);
DISPLAY 0.872340 (-2723 5350);
PAINT GREEN (-2723 5350);
DISPLAY INVISIBLE (-2723 5350);
FORCEADD TAP..1
(-1075 5050);
FORCEPROP 3 LASTPIN (-1125 5050) SIG_NAME M_F_CPU1_SA_DQ<25>
J 0
(-1115 5060);
DISPLAY 0.659574 (-1115 5060);
PAINT MONO (-1115 5060);
DISPLAY INVISIBLE (-1115 5060);
FORCEPROP 1 LASTPIN (-1125 5050) BN 25
J 0
(-1137 5058);
DISPLAY 0.680851 (-1137 5058);
PAINT GREEN (-1137 5058);
FORCEPROP 2 LAST CDS_LIB standard
J 0
(-1075 5050);
DISPLAY INVISIBLE (-1075 5050);
FORCEPROP 1 LAST BODY_TYPE PLUMBING
J 0
(-1075 5100);
DISPLAY 0.872340 (-1075 5100);
PAINT GREEN (-1075 5100);
DISPLAY INVISIBLE (-1075 5100);
FORCEPROP 1 LAST HDL_TAP TRUE
J 0
(-750 4925);
DISPLAY 0.872340 (-750 4925);
DISPLAY INVISIBLE (-750 4925);
FORCEPROP 1 LAST PATH I112
J 0
(-1077 5050);
DISPLAY 0.872340 (-1077 5050);
PAINT GREEN (-1077 5050);
DISPLAY INVISIBLE (-1077 5050);
FORCEADD TAP..1
(-1075 5100);
FORCEPROP 3 LASTPIN (-1125 5100) SIG_NAME M_F_CPU1_SA_DQ<26>
J 0
(-1115 5110);
DISPLAY 0.659574 (-1115 5110);
PAINT MONO (-1115 5110);
DISPLAY INVISIBLE (-1115 5110);
FORCEPROP 1 LASTPIN (-1125 5100) BN 26
J 0
(-1137 5108);
DISPLAY 0.680851 (-1137 5108);
PAINT GREEN (-1137 5108);
FORCEPROP 2 LAST CDS_LIB standard
J 0
(-1075 5100);
DISPLAY INVISIBLE (-1075 5100);
FORCEPROP 1 LAST BODY_TYPE PLUMBING
J 0
(-1075 5150);
DISPLAY 0.872340 (-1075 5150);
PAINT GREEN (-1075 5150);
DISPLAY INVISIBLE (-1075 5150);
FORCEPROP 1 LAST HDL_TAP TRUE
J 0
(-750 4975);
DISPLAY 0.872340 (-750 4975);
DISPLAY INVISIBLE (-750 4975);
FORCEPROP 1 LAST PATH I113
J 0
(-1077 5100);
DISPLAY 0.872340 (-1077 5100);
PAINT GREEN (-1077 5100);
DISPLAY INVISIBLE (-1077 5100);
FORCEADD TAP..1
(-1075 5150);
FORCEPROP 3 LASTPIN (-1125 5150) SIG_NAME M_F_CPU1_SA_DQ<27>
J 0
(-1115 5160);
DISPLAY 0.659574 (-1115 5160);
PAINT MONO (-1115 5160);
DISPLAY INVISIBLE (-1115 5160);
FORCEPROP 1 LASTPIN (-1125 5150) BN 27
J 0
(-1137 5158);
DISPLAY 0.680851 (-1137 5158);
PAINT GREEN (-1137 5158);
FORCEPROP 2 LAST CDS_LIB standard
J 0
(-1075 5150);
DISPLAY INVISIBLE (-1075 5150);
FORCEPROP 1 LAST BODY_TYPE PLUMBING
J 0
(-1075 5200);
DISPLAY 0.872340 (-1075 5200);
PAINT GREEN (-1075 5200);
DISPLAY INVISIBLE (-1075 5200);
FORCEPROP 1 LAST HDL_TAP TRUE
J 0
(-750 5025);
DISPLAY 0.872340 (-750 5025);
DISPLAY INVISIBLE (-750 5025);
FORCEPROP 1 LAST PATH I114
J 0
(-1077 5150);
DISPLAY 0.872340 (-1077 5150);
PAINT GREEN (-1077 5150);
DISPLAY INVISIBLE (-1077 5150);
FORCEADD TAP..1
(-1075 5200);
FORCEPROP 3 LASTPIN (-1125 5200) SIG_NAME M_F_CPU1_SA_DQ<28>
J 0
(-1115 5210);
DISPLAY 0.659574 (-1115 5210);
PAINT MONO (-1115 5210);
DISPLAY INVISIBLE (-1115 5210);
FORCEPROP 1 LASTPIN (-1125 5200) BN 28
J 0
(-1137 5208);
DISPLAY 0.680851 (-1137 5208);
PAINT GREEN (-1137 5208);
FORCEPROP 2 LAST CDS_LIB standard
J 0
(-1075 5200);
DISPLAY INVISIBLE (-1075 5200);
FORCEPROP 1 LAST BODY_TYPE PLUMBING
J 0
(-1075 5250);
DISPLAY 0.872340 (-1075 5250);
PAINT GREEN (-1075 5250);
DISPLAY INVISIBLE (-1075 5250);
FORCEPROP 1 LAST HDL_TAP TRUE
J 0
(-750 5075);
DISPLAY 0.872340 (-750 5075);
DISPLAY INVISIBLE (-750 5075);
FORCEPROP 1 LAST PATH I115
J 0
(-1077 5200);
DISPLAY 0.872340 (-1077 5200);
PAINT GREEN (-1077 5200);
DISPLAY INVISIBLE (-1077 5200);
FORCEADD TAP..1
(-1075 5300);
FORCEPROP 3 LASTPIN (-1125 5300) SIG_NAME M_F_CPU1_SA_DQ<30>
J 0
(-1115 5310);
DISPLAY 0.659574 (-1115 5310);
PAINT MONO (-1115 5310);
DISPLAY INVISIBLE (-1115 5310);
FORCEPROP 1 LASTPIN (-1125 5300) BN 30
J 0
(-1137 5308);
DISPLAY 0.680851 (-1137 5308);
PAINT GREEN (-1137 5308);
FORCEPROP 2 LAST CDS_LIB standard
J 0
(-1075 5300);
DISPLAY INVISIBLE (-1075 5300);
FORCEPROP 1 LAST BODY_TYPE PLUMBING
J 0
(-1075 5350);
DISPLAY 0.872340 (-1075 5350);
PAINT GREEN (-1075 5350);
DISPLAY INVISIBLE (-1075 5350);
FORCEPROP 1 LAST HDL_TAP TRUE
J 0
(-750 5175);
DISPLAY 0.872340 (-750 5175);
DISPLAY INVISIBLE (-750 5175);
FORCEPROP 1 LAST PATH I116
J 0
(-1077 5300);
DISPLAY 0.872340 (-1077 5300);
PAINT GREEN (-1077 5300);
DISPLAY INVISIBLE (-1077 5300);
FORCEADD TAP..1
(-1075 5250);
FORCEPROP 3 LASTPIN (-1125 5250) SIG_NAME M_F_CPU1_SA_DQ<29>
J 0
(-1115 5260);
DISPLAY 0.659574 (-1115 5260);
PAINT MONO (-1115 5260);
DISPLAY INVISIBLE (-1115 5260);
FORCEPROP 1 LASTPIN (-1125 5250) BN 29
J 0
(-1137 5258);
DISPLAY 0.680851 (-1137 5258);
PAINT GREEN (-1137 5258);
FORCEPROP 2 LAST CDS_LIB standard
J 0
(-1075 5250);
DISPLAY INVISIBLE (-1075 5250);
FORCEPROP 1 LAST BODY_TYPE PLUMBING
J 0
(-1075 5300);
DISPLAY 0.872340 (-1075 5300);
PAINT GREEN (-1075 5300);
DISPLAY INVISIBLE (-1075 5300);
FORCEPROP 1 LAST HDL_TAP TRUE
J 0
(-750 5125);
DISPLAY 0.872340 (-750 5125);
DISPLAY INVISIBLE (-750 5125);
FORCEPROP 1 LAST PATH I117
J 0
(-1077 5250);
DISPLAY 0.872340 (-1077 5250);
PAINT GREEN (-1077 5250);
DISPLAY INVISIBLE (-1077 5250);
FORCEADD TAP..1
(-1075 5350);
FORCEPROP 3 LASTPIN (-1125 5350) SIG_NAME M_F_CPU1_SA_DQ<31>
J 0
(-1115 5360);
DISPLAY 0.659574 (-1115 5360);
PAINT MONO (-1115 5360);
DISPLAY INVISIBLE (-1115 5360);
FORCEPROP 1 LASTPIN (-1125 5350) BN 31
J 0
(-1137 5358);
DISPLAY 0.680851 (-1137 5358);
PAINT GREEN (-1137 5358);
FORCEPROP 2 LAST CDS_LIB standard
J 0
(-1075 5350);
DISPLAY INVISIBLE (-1075 5350);
FORCEPROP 1 LAST BODY_TYPE PLUMBING
J 0
(-1075 5400);
DISPLAY 0.872340 (-1075 5400);
PAINT GREEN (-1075 5400);
DISPLAY INVISIBLE (-1075 5400);
FORCEPROP 1 LAST HDL_TAP TRUE
J 0
(-750 5225);
DISPLAY 0.872340 (-750 5225);
DISPLAY INVISIBLE (-750 5225);
FORCEPROP 1 LAST PATH I118
J 0
(-1077 5350);
DISPLAY 0.872340 (-1077 5350);
PAINT GREEN (-1077 5350);
DISPLAY INVISIBLE (-1077 5350);
FORCEADD OFFPAGE..3
(-250 5375);
FORCEPROP 2 LAST $XR1 109 
J 0
(54 5375);
DISPLAY 0.638298 (54 5375);
PAINT MONO (54 5375);
FORCEPROP 2 LAST $XR0 56 
J 0
(-36 5375);
DISPLAY 0.638298 (-36 5375);
PAINT MONO (-36 5375);
FORCEPROP 2 LAST CDS_LIB standard
J 2
(-250 5375);
DISPLAY INVISIBLE (-250 5375);
FORCEPROP 1 LAST OFFPAGE TRUE
J 0
(75 5250);
DISPLAY 0.872340 (75 5250);
DISPLAY INVISIBLE (75 5250);
FORCEPROP 1 LAST COMMENT_BODY TRUE
J 0
(-300 5275);
DISPLAY 0.872340 (-300 5275);
PAINT GREEN (-300 5275);
DISPLAY INVISIBLE (-300 5275);
FORCEPROP 2 LAST PATH I119
J 0
(-50 5450);
DISPLAY 1.021277 (-50 5450);
DISPLAY INVISIBLE (-50 5450);
FORCEADD OFFPAGE..3
R 2
(-3650 3525);
FORCEPROP 2 LAST $XR1 109 
J 0
(-4019 3525);
DISPLAY 0.638298 (-4019 3525);
PAINT MONO (-4019 3525);
FORCEPROP 2 LAST $XR0 56 
J 0
(-3899 3525);
DISPLAY 0.638298 (-3899 3525);
PAINT MONO (-3899 3525);
FORCEPROP 2 LAST CDS_LIB standard
J 0
(-3650 3525);
PAINT MONO (-3650 3525);
DISPLAY INVISIBLE (-3650 3525);
FORCEPROP 1 LAST OFFPAGE TRUE
J 2
(-3975 3400);
DISPLAY 0.872340 (-3975 3400);
DISPLAY INVISIBLE (-3975 3400);
FORCEPROP 1 LAST COMMENT_BODY TRUE
J 2
(-3600 3425);
DISPLAY 0.872340 (-3600 3425);
PAINT GREEN (-3600 3425);
DISPLAY INVISIBLE (-3600 3425);
FORCEPROP 2 LAST PATH I12
J 0
(-3600 3600);
DISPLAY 1.021277 (-3600 3600);
DISPLAY INVISIBLE (-3600 3600);
FORCEADD UNIVERSAL_GND..1
(650 1100);
FORCEPROP 3 LASTPIN (650 1150) SIG_NAME GND\g
J 0
(660 1160);
DISPLAY 0.659574 (660 1160);
PAINT MONO (660 1160);
DISPLAY INVISIBLE (660 1160);
FORCEPROP 1 LAST PATH I120
J 0
(725 1100);
DISPLAY 0.872340 (725 1100);
PAINT AQUA (725 1100);
DISPLAY INVISIBLE (725 1100);
FORCEPROP 1 LAST HDL_POWER GND
J 1
(675 1025);
DISPLAY 0.872340 (675 1025);
PAINT GREEN (675 1025);
DISPLAY INVISIBLE (675 1025);
FORCEPROP 2 LAST CDS_LIB logical_power
J 0
(650 1100);
PAINT MONO (650 1100);
DISPLAY INVISIBLE (650 1100);
FORCEADD Q_CAP..1
(650 1475);
FORCEPROP 1 LAST PART_NUMBER CH5221MEB00
J 0
(700 1325);
DISPLAY 0.978723 (700 1325);
DISPLAY INVISIBLE (700 1325);
FORCEPROP 1 LAST VALUE 2.2UF
J 0
(700 1525);
DISPLAY 0.978723 (700 1525);
FORCEPROP 1 LAST PACK_TYPE C0402
J 0
(700 1275);
DISPLAY 0.978723 (700 1275);
FORCEPROP 1 LAST TOLERANCE 20%
J 0
(700 1425);
DISPLAY 0.978723 (700 1425);
FORCEPROP 1 LAST VOLTAGE 6.3V
J 0
(700 1475);
DISPLAY 0.978723 (700 1475);
FORCEPROP 1 LAST MATERIAL X6S
J 0
(700 1375);
DISPLAY 0.978723 (700 1375);
FORCEPROP 1 LAST $LOCATION C87
J 0
(700 1575);
DISPLAY 0.978723 (700 1575);
FORCEPROP 1 LASTPIN (650 1575) $PN 1
J 0
(660 1555);
DISPLAY 0.787234 (660 1555);
FORCEPROP 1 LASTPIN (650 1375) $PN 2
J 0
(660 1355);
DISPLAY 0.787234 (660 1355);
FORCEPROP 2 LAST CDS_LIB pure_quanta
J 0
(650 1475);
PAINT MONO (650 1475);
DISPLAY INVISIBLE (650 1475);
FORCEPROP 1 LAST PATH I121
J 0
(700 1625);
DISPLAY 0.978723 (700 1625);
PAINT WHITE (700 1625);
DISPLAY INVISIBLE (700 1625);
FORCEPROP 1 LAST $LOCATION C87
J 0
(700 1675);
DISPLAY 1.021277 (700 1675);
DISPLAY INVISIBLE (700 1675);
FORCEPROP 2 LAST CDS_LOCATION C87
J 0
(700 1675);
DISPLAY 1.021277 (700 1675);
DISPLAY INVISIBLE (700 1675);
FORCEPROP 2 LAST $SEC 1
J 0
(700 1675);
DISPLAY 0.680851 (700 1675);
PAINT MONO (700 1675);
DISPLAY INVISIBLE (700 1675);
FORCEPROP 2 LAST CDS_SEC 1
J 0
(700 1675);
DISPLAY 1.021277 (700 1675);
DISPLAY INVISIBLE (700 1675);
FORCEADD VCC_CORE..1
(650 1800);
FORCEPROP 3 LASTPIN (650 1750) SIG_NAME P3V3_AUX\g
J 0
(660 1760);
DISPLAY 0.659574 (660 1760);
PAINT MONO (660 1760);
DISPLAY INVISIBLE (660 1760);
FORCEPROP 1 LAST HDL_POWER P3V3_AUX
J 1
(650 1850);
DISPLAY 1.148936 (650 1850);
PAINT GREEN (650 1850);
FORCEPROP 2 LAST CDS_LIB logical_power
J 0
(650 1800);
PAINT MONO (650 1800);
DISPLAY INVISIBLE (650 1800);
FORCEPROP 1 LAST PATH I122
J 0
(700 1825);
DISPLAY 0.872340 (700 1825);
PAINT AQUA (700 1825);
DISPLAY INVISIBLE (700 1825);
FORCEADD Q_CAP..1
(1650 1475);
FORCEPROP 1 LAST PART_NUMBER CH6103KEA00
J 0
(1700 1325);
DISPLAY 0.978723 (1700 1325);
DISPLAY INVISIBLE (1700 1325);
FORCEPROP 1 LAST PACK_TYPE C0805
J 0
(1700 1275);
DISPLAY 0.978723 (1700 1275);
FORCEPROP 1 LAST TOLERANCE 10%
J 0
(1700 1425);
DISPLAY 0.978723 (1700 1425);
FORCEPROP 1 LAST VOLTAGE 16V
J 0
(1700 1475);
DISPLAY 0.978723 (1700 1475);
FORCEPROP 1 LAST VALUE 10UF
J 0
(1700 1525);
DISPLAY 0.978723 (1700 1525);
FORCEPROP 1 LAST MATERIAL X6S
J 0
(1700 1375);
DISPLAY 0.978723 (1700 1375);
FORCEPROP 1 LAST $LOCATION C88
J 0
(1700 1575);
DISPLAY 0.978723 (1700 1575);
FORCEPROP 1 LASTPIN (1650 1575) $PN 1
J 0
(1660 1555);
DISPLAY 0.787234 (1660 1555);
FORCEPROP 1 LASTPIN (1650 1375) $PN 2
J 0
(1660 1355);
DISPLAY 0.787234 (1660 1355);
FORCEPROP 2 LAST CDS_LIB pure_quanta
J 0
(1650 1475);
PAINT MONO (1650 1475);
DISPLAY INVISIBLE (1650 1475);
FORCEPROP 1 LAST PATH I123
J 0
(1700 1625);
DISPLAY 0.978723 (1700 1625);
PAINT WHITE (1700 1625);
DISPLAY INVISIBLE (1700 1625);
FORCEPROP 1 LAST $LOCATION C88
J 0
(1700 1675);
DISPLAY 1.021277 (1700 1675);
DISPLAY INVISIBLE (1700 1675);
FORCEPROP 2 LAST CDS_LOCATION C88
J 0
(1700 1675);
DISPLAY 1.021277 (1700 1675);
DISPLAY INVISIBLE (1700 1675);
FORCEPROP 2 LAST $SEC 1
J 0
(1700 1675);
DISPLAY 0.680851 (1700 1675);
PAINT MONO (1700 1675);
DISPLAY INVISIBLE (1700 1675);
FORCEPROP 2 LAST CDS_SEC 1
J 0
(1700 1675);
DISPLAY 1.021277 (1700 1675);
DISPLAY INVISIBLE (1700 1675);
FORCEADD VCC_CORE..1
(1650 1800);
FORCEPROP 3 LASTPIN (1650 1750) SIG_NAME P12V_S3_AUX_CPU1_NVDIMM\g
J 0
(1660 1760);
DISPLAY 0.659574 (1660 1760);
PAINT MONO (1660 1760);
DISPLAY INVISIBLE (1660 1760);
FORCEPROP 1 LAST HDL_POWER P12V_S3_AUX_CPU1_NVDIMM
J 1
(1650 1850);
DISPLAY 1.148936 (1650 1850);
PAINT GREEN (1650 1850);
FORCEPROP 2 LAST CDS_LIB logical_power
J 0
(1650 1800);
PAINT MONO (1650 1800);
DISPLAY INVISIBLE (1650 1800);
FORCEPROP 1 LAST PATH I124
J 0
(1700 1825);
DISPLAY 0.872340 (1700 1825);
PAINT AQUA (1700 1825);
DISPLAY INVISIBLE (1700 1825);
FORCEADD TAP..1
(1675 3400);
FORCEPROP 3 LASTPIN (1625 3400) SIG_NAME M_F_CPU1_SB_DQS_DP<0>
J 0
(1635 3410);
DISPLAY 0.659574 (1635 3410);
PAINT MONO (1635 3410);
DISPLAY INVISIBLE (1635 3410);
FORCEPROP 1 LASTPIN (1625 3400) BN 0
J 0
(1613 3408);
DISPLAY 0.680851 (1613 3408);
PAINT GREEN (1613 3408);
FORCEPROP 2 LAST CDS_LIB standard
J 0
(1675 3400);
PAINT MONO (1675 3400);
DISPLAY INVISIBLE (1675 3400);
FORCEPROP 1 LAST BODY_TYPE PLUMBING
J 0
(1675 3450);
DISPLAY 0.872340 (1675 3450);
PAINT GREEN (1675 3450);
DISPLAY INVISIBLE (1675 3450);
FORCEPROP 1 LAST HDL_TAP TRUE
J 0
(2000 3275);
DISPLAY 0.872340 (2000 3275);
DISPLAY INVISIBLE (2000 3275);
FORCEPROP 1 LAST PATH I126
J 0
(1673 3400);
DISPLAY 0.872340 (1673 3400);
PAINT GREEN (1673 3400);
DISPLAY INVISIBLE (1673 3400);
FORCEADD TAP..1
(1675 3500);
FORCEPROP 3 LASTPIN (1625 3500) SIG_NAME M_F_CPU1_SB_DQS_DP<1>
J 0
(1635 3510);
DISPLAY 0.659574 (1635 3510);
PAINT MONO (1635 3510);
DISPLAY INVISIBLE (1635 3510);
FORCEPROP 1 LASTPIN (1625 3500) BN 1
J 0
(1613 3508);
DISPLAY 0.680851 (1613 3508);
PAINT GREEN (1613 3508);
FORCEPROP 2 LAST CDS_LIB standard
J 0
(1675 3500);
DISPLAY INVISIBLE (1675 3500);
FORCEPROP 1 LAST BODY_TYPE PLUMBING
J 0
(1675 3550);
DISPLAY 0.872340 (1675 3550);
PAINT GREEN (1675 3550);
DISPLAY INVISIBLE (1675 3550);
FORCEPROP 1 LAST HDL_TAP TRUE
J 0
(2000 3375);
DISPLAY 0.872340 (2000 3375);
DISPLAY INVISIBLE (2000 3375);
FORCEPROP 1 LAST PATH I127
J 0
(1673 3500);
DISPLAY 0.872340 (1673 3500);
PAINT GREEN (1673 3500);
DISPLAY INVISIBLE (1673 3500);
FORCEADD TAP..1
(1850 3350);
FORCEPROP 3 LASTPIN (1800 3350) SIG_NAME M_F_CPU1_SB_DQS_DN<0>
J 0
(1810 3360);
DISPLAY 0.659574 (1810 3360);
PAINT MONO (1810 3360);
DISPLAY INVISIBLE (1810 3360);
FORCEPROP 1 LASTPIN (1800 3350) BN 0
J 0
(1788 3358);
DISPLAY 0.680851 (1788 3358);
PAINT GREEN (1788 3358);
FORCEPROP 2 LAST CDS_LIB standard
J 0
(1850 3350);
PAINT MONO (1850 3350);
DISPLAY INVISIBLE (1850 3350);
FORCEPROP 1 LAST BODY_TYPE PLUMBING
J 0
(1850 3400);
DISPLAY 0.872340 (1850 3400);
PAINT GREEN (1850 3400);
DISPLAY INVISIBLE (1850 3400);
FORCEPROP 1 LAST HDL_TAP TRUE
J 0
(2175 3225);
DISPLAY 0.872340 (2175 3225);
DISPLAY INVISIBLE (2175 3225);
FORCEPROP 1 LAST PATH I128
J 0
(1848 3350);
DISPLAY 0.872340 (1848 3350);
PAINT GREEN (1848 3350);
DISPLAY INVISIBLE (1848 3350);
FORCEADD TAP..1
(1850 3450);
FORCEPROP 3 LASTPIN (1800 3450) SIG_NAME M_F_CPU1_SB_DQS_DN<1>
J 0
(1810 3460);
DISPLAY 0.659574 (1810 3460);
PAINT MONO (1810 3460);
DISPLAY INVISIBLE (1810 3460);
FORCEPROP 1 LASTPIN (1800 3450) BN 1
J 0
(1788 3458);
DISPLAY 0.680851 (1788 3458);
PAINT GREEN (1788 3458);
FORCEPROP 2 LAST CDS_LIB standard
J 0
(1850 3450);
DISPLAY INVISIBLE (1850 3450);
FORCEPROP 1 LAST BODY_TYPE PLUMBING
J 0
(1850 3500);
DISPLAY 0.872340 (1850 3500);
PAINT GREEN (1850 3500);
DISPLAY INVISIBLE (1850 3500);
FORCEPROP 1 LAST HDL_TAP TRUE
J 0
(2175 3325);
DISPLAY 0.872340 (2175 3325);
DISPLAY INVISIBLE (2175 3325);
FORCEPROP 1 LAST PATH I129
J 0
(1848 3450);
DISPLAY 0.872340 (1848 3450);
PAINT GREEN (1848 3450);
DISPLAY INVISIBLE (1848 3450);
FORCEADD OFFPAGE..3
R 2
(-3650 3975);
FORCEPROP 2 LAST $XR1 109 
J 0
(-4019 3975);
DISPLAY 0.638298 (-4019 3975);
PAINT MONO (-4019 3975);
FORCEPROP 2 LAST $XR0 56 
J 0
(-3899 3975);
DISPLAY 0.638298 (-3899 3975);
PAINT MONO (-3899 3975);
FORCEPROP 2 LAST CDS_LIB standard
J 0
(-3650 3975);
PAINT MONO (-3650 3975);
DISPLAY INVISIBLE (-3650 3975);
FORCEPROP 1 LAST OFFPAGE TRUE
J 2
(-3975 3850);
DISPLAY 0.872340 (-3975 3850);
DISPLAY INVISIBLE (-3975 3850);
FORCEPROP 1 LAST COMMENT_BODY TRUE
J 2
(-3600 3875);
DISPLAY 0.872340 (-3600 3875);
PAINT GREEN (-3600 3875);
DISPLAY INVISIBLE (-3600 3875);
FORCEPROP 2 LAST PATH I13
J 0
(-3600 4050);
DISPLAY 1.021277 (-3600 4050);
DISPLAY INVISIBLE (-3600 4050);
FORCEADD TAP..1
(1675 3600);
FORCEPROP 3 LASTPIN (1625 3600) SIG_NAME M_F_CPU1_SB_DQS_DP<2>
J 0
(1635 3610);
DISPLAY 0.659574 (1635 3610);
PAINT MONO (1635 3610);
DISPLAY INVISIBLE (1635 3610);
FORCEPROP 1 LASTPIN (1625 3600) BN 2
J 0
(1613 3608);
DISPLAY 0.680851 (1613 3608);
PAINT GREEN (1613 3608);
FORCEPROP 2 LAST CDS_LIB standard
J 0
(1675 3600);
DISPLAY INVISIBLE (1675 3600);
FORCEPROP 1 LAST BODY_TYPE PLUMBING
J 0
(1675 3650);
DISPLAY 0.872340 (1675 3650);
PAINT GREEN (1675 3650);
DISPLAY INVISIBLE (1675 3650);
FORCEPROP 1 LAST HDL_TAP TRUE
J 0
(2000 3475);
DISPLAY 0.872340 (2000 3475);
DISPLAY INVISIBLE (2000 3475);
FORCEPROP 1 LAST PATH I130
J 0
(1673 3600);
DISPLAY 0.872340 (1673 3600);
PAINT GREEN (1673 3600);
DISPLAY INVISIBLE (1673 3600);
FORCEADD TAP..1
(1675 3700);
FORCEPROP 3 LASTPIN (1625 3700) SIG_NAME M_F_CPU1_SB_DQS_DP<3>
J 0
(1635 3710);
DISPLAY 0.659574 (1635 3710);
PAINT MONO (1635 3710);
DISPLAY INVISIBLE (1635 3710);
FORCEPROP 1 LASTPIN (1625 3700) BN 3
J 0
(1613 3708);
DISPLAY 0.680851 (1613 3708);
PAINT GREEN (1613 3708);
FORCEPROP 2 LAST CDS_LIB standard
J 0
(1675 3700);
PAINT MONO (1675 3700);
DISPLAY INVISIBLE (1675 3700);
FORCEPROP 1 LAST BODY_TYPE PLUMBING
J 0
(1675 3750);
DISPLAY 0.872340 (1675 3750);
PAINT GREEN (1675 3750);
DISPLAY INVISIBLE (1675 3750);
FORCEPROP 1 LAST HDL_TAP TRUE
J 0
(2000 3575);
DISPLAY 0.872340 (2000 3575);
DISPLAY INVISIBLE (2000 3575);
FORCEPROP 1 LAST PATH I131
J 0
(1673 3700);
DISPLAY 0.872340 (1673 3700);
PAINT GREEN (1673 3700);
DISPLAY INVISIBLE (1673 3700);
FORCEADD TAP..1
(1850 3550);
FORCEPROP 3 LASTPIN (1800 3550) SIG_NAME M_F_CPU1_SB_DQS_DN<2>
J 0
(1810 3560);
DISPLAY 0.659574 (1810 3560);
PAINT MONO (1810 3560);
DISPLAY INVISIBLE (1810 3560);
FORCEPROP 1 LASTPIN (1800 3550) BN 2
J 0
(1788 3558);
DISPLAY 0.680851 (1788 3558);
PAINT GREEN (1788 3558);
FORCEPROP 2 LAST CDS_LIB standard
J 0
(1850 3550);
DISPLAY INVISIBLE (1850 3550);
FORCEPROP 1 LAST BODY_TYPE PLUMBING
J 0
(1850 3600);
DISPLAY 0.872340 (1850 3600);
PAINT GREEN (1850 3600);
DISPLAY INVISIBLE (1850 3600);
FORCEPROP 1 LAST HDL_TAP TRUE
J 0
(2175 3425);
DISPLAY 0.872340 (2175 3425);
DISPLAY INVISIBLE (2175 3425);
FORCEPROP 1 LAST PATH I132
J 0
(1848 3550);
DISPLAY 0.872340 (1848 3550);
PAINT GREEN (1848 3550);
DISPLAY INVISIBLE (1848 3550);
FORCEADD TAP..1
(1850 3750);
FORCEPROP 3 LASTPIN (1800 3750) SIG_NAME M_F_CPU1_SB_DQS_DN<4>
J 0
(1810 3760);
DISPLAY 0.659574 (1810 3760);
PAINT MONO (1810 3760);
DISPLAY INVISIBLE (1810 3760);
FORCEPROP 1 LASTPIN (1800 3750) BN 4
J 0
(1788 3758);
DISPLAY 0.680851 (1788 3758);
PAINT GREEN (1788 3758);
FORCEPROP 2 LAST CDS_LIB standard
J 0
(1850 3750);
PAINT MONO (1850 3750);
DISPLAY INVISIBLE (1850 3750);
FORCEPROP 1 LAST BODY_TYPE PLUMBING
J 0
(1850 3800);
DISPLAY 0.872340 (1850 3800);
PAINT GREEN (1850 3800);
DISPLAY INVISIBLE (1850 3800);
FORCEPROP 1 LAST HDL_TAP TRUE
J 0
(2175 3625);
DISPLAY 0.872340 (2175 3625);
DISPLAY INVISIBLE (2175 3625);
FORCEPROP 1 LAST PATH I133
J 0
(1848 3750);
DISPLAY 0.872340 (1848 3750);
PAINT GREEN (1848 3750);
DISPLAY INVISIBLE (1848 3750);
FORCEADD TAP..1
(1850 3650);
FORCEPROP 3 LASTPIN (1800 3650) SIG_NAME M_F_CPU1_SB_DQS_DN<3>
J 0
(1810 3660);
DISPLAY 0.659574 (1810 3660);
PAINT MONO (1810 3660);
DISPLAY INVISIBLE (1810 3660);
FORCEPROP 1 LASTPIN (1800 3650) BN 3
J 0
(1788 3658);
DISPLAY 0.680851 (1788 3658);
PAINT GREEN (1788 3658);
FORCEPROP 2 LAST CDS_LIB standard
J 0
(1850 3650);
PAINT MONO (1850 3650);
DISPLAY INVISIBLE (1850 3650);
FORCEPROP 1 LAST BODY_TYPE PLUMBING
J 0
(1850 3700);
DISPLAY 0.872340 (1850 3700);
PAINT GREEN (1850 3700);
DISPLAY INVISIBLE (1850 3700);
FORCEPROP 1 LAST HDL_TAP TRUE
J 0
(2175 3525);
DISPLAY 0.872340 (2175 3525);
DISPLAY INVISIBLE (2175 3525);
FORCEPROP 1 LAST PATH I134
J 0
(1848 3650);
DISPLAY 0.872340 (1848 3650);
PAINT GREEN (1848 3650);
DISPLAY INVISIBLE (1848 3650);
FORCEADD TAP..1
(1675 3800);
FORCEPROP 3 LASTPIN (1625 3800) SIG_NAME M_F_CPU1_SB_DQS_DP<4>
J 0
(1635 3810);
DISPLAY 0.659574 (1635 3810);
PAINT MONO (1635 3810);
DISPLAY INVISIBLE (1635 3810);
FORCEPROP 1 LASTPIN (1625 3800) BN 4
J 0
(1613 3808);
DISPLAY 0.680851 (1613 3808);
PAINT GREEN (1613 3808);
FORCEPROP 2 LAST CDS_LIB standard
J 0
(1675 3800);
PAINT MONO (1675 3800);
DISPLAY INVISIBLE (1675 3800);
FORCEPROP 1 LAST BODY_TYPE PLUMBING
J 0
(1675 3850);
DISPLAY 0.872340 (1675 3850);
PAINT GREEN (1675 3850);
DISPLAY INVISIBLE (1675 3850);
FORCEPROP 1 LAST HDL_TAP TRUE
J 0
(2000 3675);
DISPLAY 0.872340 (2000 3675);
DISPLAY INVISIBLE (2000 3675);
FORCEPROP 1 LAST PATH I135
J 0
(1673 3800);
DISPLAY 0.872340 (1673 3800);
PAINT GREEN (1673 3800);
DISPLAY INVISIBLE (1673 3800);
FORCEADD TAP..1
(1675 4000);
FORCEPROP 3 LASTPIN (1625 4000) SIG_NAME M_F_CPU1_SB_DQS_DP<6>
J 0
(1635 4010);
DISPLAY 0.659574 (1635 4010);
PAINT MONO (1635 4010);
DISPLAY INVISIBLE (1635 4010);
FORCEPROP 1 LASTPIN (1625 4000) BN 6
J 0
(1613 4008);
DISPLAY 0.680851 (1613 4008);
PAINT GREEN (1613 4008);
FORCEPROP 2 LAST CDS_LIB standard
J 0
(1675 4000);
DISPLAY INVISIBLE (1675 4000);
FORCEPROP 1 LAST BODY_TYPE PLUMBING
J 0
(1675 4050);
DISPLAY 0.872340 (1675 4050);
PAINT GREEN (1675 4050);
DISPLAY INVISIBLE (1675 4050);
FORCEPROP 1 LAST HDL_TAP TRUE
J 0
(2000 3875);
DISPLAY 0.872340 (2000 3875);
DISPLAY INVISIBLE (2000 3875);
FORCEPROP 1 LAST PATH I136
J 0
(1673 4000);
DISPLAY 0.872340 (1673 4000);
PAINT GREEN (1673 4000);
DISPLAY INVISIBLE (1673 4000);
FORCEADD TAP..1
(1675 3900);
FORCEPROP 3 LASTPIN (1625 3900) SIG_NAME M_F_CPU1_SB_DQS_DP<5>
J 0
(1635 3910);
DISPLAY 0.659574 (1635 3910);
PAINT MONO (1635 3910);
DISPLAY INVISIBLE (1635 3910);
FORCEPROP 1 LASTPIN (1625 3900) BN 5
J 0
(1613 3908);
DISPLAY 0.680851 (1613 3908);
PAINT GREEN (1613 3908);
FORCEPROP 2 LAST CDS_LIB standard
J 0
(1675 3900);
DISPLAY INVISIBLE (1675 3900);
FORCEPROP 1 LAST BODY_TYPE PLUMBING
J 0
(1675 3950);
DISPLAY 0.872340 (1675 3950);
PAINT GREEN (1675 3950);
DISPLAY INVISIBLE (1675 3950);
FORCEPROP 1 LAST HDL_TAP TRUE
J 0
(2000 3775);
DISPLAY 0.872340 (2000 3775);
DISPLAY INVISIBLE (2000 3775);
FORCEPROP 1 LAST PATH I137
J 0
(1673 3900);
DISPLAY 0.872340 (1673 3900);
PAINT GREEN (1673 3900);
DISPLAY INVISIBLE (1673 3900);
FORCEADD TAP..1
(1850 3850);
FORCEPROP 3 LASTPIN (1800 3850) SIG_NAME M_F_CPU1_SB_DQS_DN<5>
J 0
(1810 3860);
DISPLAY 0.659574 (1810 3860);
PAINT MONO (1810 3860);
DISPLAY INVISIBLE (1810 3860);
FORCEPROP 1 LASTPIN (1800 3850) BN 5
J 0
(1788 3858);
DISPLAY 0.680851 (1788 3858);
PAINT GREEN (1788 3858);
FORCEPROP 2 LAST CDS_LIB standard
J 0
(1850 3850);
DISPLAY INVISIBLE (1850 3850);
FORCEPROP 1 LAST BODY_TYPE PLUMBING
J 0
(1850 3900);
DISPLAY 0.872340 (1850 3900);
PAINT GREEN (1850 3900);
DISPLAY INVISIBLE (1850 3900);
FORCEPROP 1 LAST HDL_TAP TRUE
J 0
(2175 3725);
DISPLAY 0.872340 (2175 3725);
DISPLAY INVISIBLE (2175 3725);
FORCEPROP 1 LAST PATH I138
J 0
(1848 3850);
DISPLAY 0.872340 (1848 3850);
PAINT GREEN (1848 3850);
DISPLAY INVISIBLE (1848 3850);
FORCEADD TAP..1
(1850 3950);
FORCEPROP 3 LASTPIN (1800 3950) SIG_NAME M_F_CPU1_SB_DQS_DN<6>
J 0
(1810 3960);
DISPLAY 0.659574 (1810 3960);
PAINT MONO (1810 3960);
DISPLAY INVISIBLE (1810 3960);
FORCEPROP 1 LASTPIN (1800 3950) BN 6
J 0
(1788 3958);
DISPLAY 0.680851 (1788 3958);
PAINT GREEN (1788 3958);
FORCEPROP 2 LAST CDS_LIB standard
J 0
(1850 3950);
DISPLAY INVISIBLE (1850 3950);
FORCEPROP 1 LAST BODY_TYPE PLUMBING
J 0
(1850 4000);
DISPLAY 0.872340 (1850 4000);
PAINT GREEN (1850 4000);
DISPLAY INVISIBLE (1850 4000);
FORCEPROP 1 LAST HDL_TAP TRUE
J 0
(2175 3825);
DISPLAY 0.872340 (2175 3825);
DISPLAY INVISIBLE (2175 3825);
FORCEPROP 1 LAST PATH I139
J 0
(1848 3950);
DISPLAY 0.872340 (1848 3950);
PAINT GREEN (1848 3950);
DISPLAY INVISIBLE (1848 3950);
FORCEADD OFFPAGE..1
(-3650 4050);
FORCEPROP 2 LAST $XR0 56 
J 0
(-3871 4050);
DISPLAY 0.638298 (-3871 4050);
PAINT MONO (-3871 4050);
FORCEPROP 2 LAST CDS_LIB standard
J 0
(-3650 4050);
PAINT MONO (-3650 4050);
DISPLAY INVISIBLE (-3650 4050);
FORCEPROP 1 LAST OFFPAGE TRUE
J 0
(-3325 3925);
DISPLAY 0.872340 (-3325 3925);
DISPLAY INVISIBLE (-3325 3925);
FORCEPROP 1 LAST COMMENT_BODY TRUE
J 0
(-3525 3950);
DISPLAY 0.872340 (-3525 3950);
PAINT GREEN (-3525 3950);
DISPLAY INVISIBLE (-3525 3950);
FORCEPROP 2 LAST PATH I14
J 0
(-3600 4125);
DISPLAY 1.021277 (-3600 4125);
DISPLAY INVISIBLE (-3600 4125);
FORCEADD TAP..1
(1675 4100);
FORCEPROP 3 LASTPIN (1625 4100) SIG_NAME M_F_CPU1_SB_DQS_DP<7>
J 0
(1635 4110);
DISPLAY 0.659574 (1635 4110);
PAINT MONO (1635 4110);
DISPLAY INVISIBLE (1635 4110);
FORCEPROP 1 LASTPIN (1625 4100) BN 7
J 0
(1613 4108);
DISPLAY 0.680851 (1613 4108);
PAINT GREEN (1613 4108);
FORCEPROP 2 LAST CDS_LIB standard
J 0
(1675 4100);
DISPLAY INVISIBLE (1675 4100);
FORCEPROP 1 LAST BODY_TYPE PLUMBING
J 0
(1675 4150);
DISPLAY 0.872340 (1675 4150);
PAINT GREEN (1675 4150);
DISPLAY INVISIBLE (1675 4150);
FORCEPROP 1 LAST HDL_TAP TRUE
J 0
(2000 3975);
DISPLAY 0.872340 (2000 3975);
DISPLAY INVISIBLE (2000 3975);
FORCEPROP 1 LAST PATH I140
J 0
(1673 4100);
DISPLAY 0.872340 (1673 4100);
PAINT GREEN (1673 4100);
DISPLAY INVISIBLE (1673 4100);
FORCEADD TAP..1
(1675 4200);
FORCEPROP 3 LASTPIN (1625 4200) SIG_NAME M_F_CPU1_SB_DQS_DP<8>
J 0
(1635 4210);
DISPLAY 0.659574 (1635 4210);
PAINT MONO (1635 4210);
DISPLAY INVISIBLE (1635 4210);
FORCEPROP 1 LASTPIN (1625 4200) BN 8
J 0
(1613 4208);
DISPLAY 0.680851 (1613 4208);
PAINT GREEN (1613 4208);
FORCEPROP 2 LAST CDS_LIB standard
J 0
(1675 4200);
DISPLAY INVISIBLE (1675 4200);
FORCEPROP 1 LAST BODY_TYPE PLUMBING
J 0
(1675 4250);
DISPLAY 0.872340 (1675 4250);
PAINT GREEN (1675 4250);
DISPLAY INVISIBLE (1675 4250);
FORCEPROP 1 LAST HDL_TAP TRUE
J 0
(2000 4075);
DISPLAY 0.872340 (2000 4075);
DISPLAY INVISIBLE (2000 4075);
FORCEPROP 1 LAST PATH I141
J 0
(1673 4200);
DISPLAY 0.872340 (1673 4200);
PAINT GREEN (1673 4200);
DISPLAY INVISIBLE (1673 4200);
FORCEADD TAP..1
(1850 4050);
FORCEPROP 3 LASTPIN (1800 4050) SIG_NAME M_F_CPU1_SB_DQS_DN<7>
J 0
(1810 4060);
DISPLAY 0.659574 (1810 4060);
PAINT MONO (1810 4060);
DISPLAY INVISIBLE (1810 4060);
FORCEPROP 1 LASTPIN (1800 4050) BN 7
J 0
(1788 4058);
DISPLAY 0.680851 (1788 4058);
PAINT GREEN (1788 4058);
FORCEPROP 2 LAST CDS_LIB standard
J 0
(1850 4050);
DISPLAY INVISIBLE (1850 4050);
FORCEPROP 1 LAST BODY_TYPE PLUMBING
J 0
(1850 4100);
DISPLAY 0.872340 (1850 4100);
PAINT GREEN (1850 4100);
DISPLAY INVISIBLE (1850 4100);
FORCEPROP 1 LAST HDL_TAP TRUE
J 0
(2175 3925);
DISPLAY 0.872340 (2175 3925);
DISPLAY INVISIBLE (2175 3925);
FORCEPROP 1 LAST PATH I142
J 0
(1848 4050);
DISPLAY 0.872340 (1848 4050);
PAINT GREEN (1848 4050);
DISPLAY INVISIBLE (1848 4050);
FORCEADD TAP..1
(1850 4150);
FORCEPROP 3 LASTPIN (1800 4150) SIG_NAME M_F_CPU1_SB_DQS_DN<8>
J 0
(1810 4160);
DISPLAY 0.659574 (1810 4160);
PAINT MONO (1810 4160);
DISPLAY INVISIBLE (1810 4160);
FORCEPROP 1 LASTPIN (1800 4150) BN 8
J 0
(1788 4158);
DISPLAY 0.680851 (1788 4158);
PAINT GREEN (1788 4158);
FORCEPROP 2 LAST CDS_LIB standard
J 0
(1850 4150);
DISPLAY INVISIBLE (1850 4150);
FORCEPROP 1 LAST BODY_TYPE PLUMBING
J 0
(1850 4200);
DISPLAY 0.872340 (1850 4200);
PAINT GREEN (1850 4200);
DISPLAY INVISIBLE (1850 4200);
FORCEPROP 1 LAST HDL_TAP TRUE
J 0
(2175 4025);
DISPLAY 0.872340 (2175 4025);
DISPLAY INVISIBLE (2175 4025);
FORCEPROP 1 LAST PATH I143
J 0
(1848 4150);
DISPLAY 0.872340 (1848 4150);
PAINT GREEN (1848 4150);
DISPLAY INVISIBLE (1848 4150);
FORCEADD TAP..1
(1850 4250);
FORCEPROP 3 LASTPIN (1800 4250) SIG_NAME M_F_CPU1_SB_DQS_DN<9>
J 0
(1810 4260);
DISPLAY 0.659574 (1810 4260);
PAINT MONO (1810 4260);
DISPLAY INVISIBLE (1810 4260);
FORCEPROP 1 LASTPIN (1800 4250) BN 9
J 0
(1788 4258);
DISPLAY 0.680851 (1788 4258);
PAINT GREEN (1788 4258);
FORCEPROP 2 LAST CDS_LIB standard
J 0
(1850 4250);
DISPLAY INVISIBLE (1850 4250);
FORCEPROP 1 LAST BODY_TYPE PLUMBING
J 0
(1850 4300);
DISPLAY 0.872340 (1850 4300);
PAINT GREEN (1850 4300);
DISPLAY INVISIBLE (1850 4300);
FORCEPROP 1 LAST HDL_TAP TRUE
J 0
(2175 4125);
DISPLAY 0.872340 (2175 4125);
DISPLAY INVISIBLE (2175 4125);
FORCEPROP 1 LAST PATH I144
J 0
(1848 4250);
DISPLAY 0.872340 (1848 4250);
PAINT GREEN (1848 4250);
DISPLAY INVISIBLE (1848 4250);
FORCEADD TAP..1
(1675 4300);
FORCEPROP 3 LASTPIN (1625 4300) SIG_NAME M_F_CPU1_SB_DQS_DP<9>
J 0
(1635 4310);
DISPLAY 0.659574 (1635 4310);
PAINT MONO (1635 4310);
DISPLAY INVISIBLE (1635 4310);
FORCEPROP 1 LASTPIN (1625 4300) BN 9
J 0
(1613 4308);
DISPLAY 0.680851 (1613 4308);
PAINT GREEN (1613 4308);
FORCEPROP 2 LAST CDS_LIB standard
J 0
(1675 4300);
DISPLAY INVISIBLE (1675 4300);
FORCEPROP 1 LAST BODY_TYPE PLUMBING
J 0
(1675 4350);
DISPLAY 0.872340 (1675 4350);
PAINT GREEN (1675 4350);
DISPLAY INVISIBLE (1675 4350);
FORCEPROP 1 LAST HDL_TAP TRUE
J 0
(2000 4175);
DISPLAY 0.872340 (2000 4175);
DISPLAY INVISIBLE (2000 4175);
FORCEPROP 1 LAST PATH I145
J 0
(1673 4300);
DISPLAY 0.872340 (1673 4300);
PAINT GREEN (1673 4300);
DISPLAY INVISIBLE (1673 4300);
FORCEADD TAP..1
(1675 4450);
FORCEPROP 3 LASTPIN (1625 4450) SIG_NAME M_F_CPU1_SA_DQS_DP<0>
J 0
(1635 4460);
DISPLAY 0.659574 (1635 4460);
PAINT MONO (1635 4460);
DISPLAY INVISIBLE (1635 4460);
FORCEPROP 1 LASTPIN (1625 4450) BN 0
J 0
(1613 4458);
DISPLAY 0.680851 (1613 4458);
PAINT GREEN (1613 4458);
FORCEPROP 2 LAST CDS_LIB standard
J 0
(1675 4450);
PAINT MONO (1675 4450);
DISPLAY INVISIBLE (1675 4450);
FORCEPROP 1 LAST BODY_TYPE PLUMBING
J 0
(1675 4500);
DISPLAY 0.872340 (1675 4500);
PAINT GREEN (1675 4500);
DISPLAY INVISIBLE (1675 4500);
FORCEPROP 1 LAST HDL_TAP TRUE
J 0
(2000 4325);
DISPLAY 0.872340 (2000 4325);
DISPLAY INVISIBLE (2000 4325);
FORCEPROP 1 LAST PATH I146
J 0
(1673 4450);
DISPLAY 0.872340 (1673 4450);
PAINT GREEN (1673 4450);
DISPLAY INVISIBLE (1673 4450);
FORCEADD TAP..1
(1850 4400);
FORCEPROP 3 LASTPIN (1800 4400) SIG_NAME M_F_CPU1_SA_DQS_DN<0>
J 0
(1810 4410);
DISPLAY 0.659574 (1810 4410);
PAINT MONO (1810 4410);
DISPLAY INVISIBLE (1810 4410);
FORCEPROP 1 LASTPIN (1800 4400) BN 0
J 0
(1788 4408);
DISPLAY 0.680851 (1788 4408);
PAINT GREEN (1788 4408);
FORCEPROP 2 LAST CDS_LIB standard
J 0
(1850 4400);
PAINT MONO (1850 4400);
DISPLAY INVISIBLE (1850 4400);
FORCEPROP 1 LAST BODY_TYPE PLUMBING
J 0
(1850 4450);
DISPLAY 0.872340 (1850 4450);
PAINT GREEN (1850 4450);
DISPLAY INVISIBLE (1850 4450);
FORCEPROP 1 LAST HDL_TAP TRUE
J 0
(2175 4275);
DISPLAY 0.872340 (2175 4275);
DISPLAY INVISIBLE (2175 4275);
FORCEPROP 1 LAST PATH I147
J 0
(1848 4400);
DISPLAY 0.872340 (1848 4400);
PAINT GREEN (1848 4400);
DISPLAY INVISIBLE (1848 4400);
FORCEADD TAP..1
(1850 4500);
FORCEPROP 3 LASTPIN (1800 4500) SIG_NAME M_F_CPU1_SA_DQS_DN<1>
J 0
(1810 4510);
DISPLAY 0.659574 (1810 4510);
PAINT MONO (1810 4510);
DISPLAY INVISIBLE (1810 4510);
FORCEPROP 1 LASTPIN (1800 4500) BN 1
J 0
(1788 4508);
DISPLAY 0.680851 (1788 4508);
PAINT GREEN (1788 4508);
FORCEPROP 2 LAST CDS_LIB standard
J 0
(1850 4500);
DISPLAY INVISIBLE (1850 4500);
FORCEPROP 1 LAST BODY_TYPE PLUMBING
J 0
(1850 4550);
DISPLAY 0.872340 (1850 4550);
PAINT GREEN (1850 4550);
DISPLAY INVISIBLE (1850 4550);
FORCEPROP 1 LAST HDL_TAP TRUE
J 0
(2175 4375);
DISPLAY 0.872340 (2175 4375);
DISPLAY INVISIBLE (2175 4375);
FORCEPROP 1 LAST PATH I148
J 0
(1848 4500);
DISPLAY 0.872340 (1848 4500);
PAINT GREEN (1848 4500);
DISPLAY INVISIBLE (1848 4500);
FORCEADD TAP..1
(1675 4650);
FORCEPROP 3 LASTPIN (1625 4650) SIG_NAME M_F_CPU1_SA_DQS_DP<2>
J 0
(1635 4660);
DISPLAY 0.659574 (1635 4660);
PAINT MONO (1635 4660);
DISPLAY INVISIBLE (1635 4660);
FORCEPROP 1 LASTPIN (1625 4650) BN 2
J 0
(1613 4658);
DISPLAY 0.680851 (1613 4658);
PAINT GREEN (1613 4658);
FORCEPROP 2 LAST CDS_LIB standard
J 0
(1675 4650);
DISPLAY INVISIBLE (1675 4650);
FORCEPROP 1 LAST BODY_TYPE PLUMBING
J 0
(1675 4700);
DISPLAY 0.872340 (1675 4700);
PAINT GREEN (1675 4700);
DISPLAY INVISIBLE (1675 4700);
FORCEPROP 1 LAST HDL_TAP TRUE
J 0
(2000 4525);
DISPLAY 0.872340 (2000 4525);
DISPLAY INVISIBLE (2000 4525);
FORCEPROP 1 LAST PATH I149
J 0
(1673 4650);
DISPLAY 0.872340 (1673 4650);
PAINT GREEN (1673 4650);
DISPLAY INVISIBLE (1673 4650);
FORCEADD VCC_CORE..1
(-3550 3225);
FORCEPROP 3 LASTPIN (-3550 3175) SIG_NAME P3V3_AUX\g
J 0
(-3540 3185);
DISPLAY 0.659574 (-3540 3185);
PAINT MONO (-3540 3185);
DISPLAY INVISIBLE (-3540 3185);
FORCEPROP 1 LAST HDL_POWER P3V3_AUX
J 1
(-3550 3275);
DISPLAY 1.148936 (-3550 3275);
PAINT GREEN (-3550 3275);
FORCEPROP 2 LAST CDS_LIB logical_power
J 0
(-3550 3225);
PAINT MONO (-3550 3225);
DISPLAY INVISIBLE (-3550 3225);
FORCEPROP 1 LAST PATH I15
J 0
(-3500 3250);
DISPLAY 0.872340 (-3500 3250);
PAINT AQUA (-3500 3250);
DISPLAY INVISIBLE (-3500 3250);
FORCEADD TAP..1
(1675 4550);
FORCEPROP 3 LASTPIN (1625 4550) SIG_NAME M_F_CPU1_SA_DQS_DP<1>
J 0
(1635 4560);
DISPLAY 0.659574 (1635 4560);
PAINT MONO (1635 4560);
DISPLAY INVISIBLE (1635 4560);
FORCEPROP 1 LASTPIN (1625 4550) BN 1
J 0
(1613 4558);
DISPLAY 0.680851 (1613 4558);
PAINT GREEN (1613 4558);
FORCEPROP 2 LAST CDS_LIB standard
J 0
(1675 4550);
DISPLAY INVISIBLE (1675 4550);
FORCEPROP 1 LAST BODY_TYPE PLUMBING
J 0
(1675 4600);
DISPLAY 0.872340 (1675 4600);
PAINT GREEN (1675 4600);
DISPLAY INVISIBLE (1675 4600);
FORCEPROP 1 LAST HDL_TAP TRUE
J 0
(2000 4425);
DISPLAY 0.872340 (2000 4425);
DISPLAY INVISIBLE (2000 4425);
FORCEPROP 1 LAST PATH I150
J 0
(1673 4550);
DISPLAY 0.872340 (1673 4550);
PAINT GREEN (1673 4550);
DISPLAY INVISIBLE (1673 4550);
FORCEADD TAP..1
(1675 4750);
FORCEPROP 3 LASTPIN (1625 4750) SIG_NAME M_F_CPU1_SA_DQS_DP<3>
J 0
(1635 4760);
DISPLAY 0.659574 (1635 4760);
PAINT MONO (1635 4760);
DISPLAY INVISIBLE (1635 4760);
FORCEPROP 1 LASTPIN (1625 4750) BN 3
J 0
(1613 4758);
DISPLAY 0.680851 (1613 4758);
PAINT GREEN (1613 4758);
FORCEPROP 2 LAST CDS_LIB standard
J 0
(1675 4750);
PAINT MONO (1675 4750);
DISPLAY INVISIBLE (1675 4750);
FORCEPROP 1 LAST BODY_TYPE PLUMBING
J 0
(1675 4800);
DISPLAY 0.872340 (1675 4800);
PAINT GREEN (1675 4800);
DISPLAY INVISIBLE (1675 4800);
FORCEPROP 1 LAST HDL_TAP TRUE
J 0
(2000 4625);
DISPLAY 0.872340 (2000 4625);
DISPLAY INVISIBLE (2000 4625);
FORCEPROP 1 LAST PATH I151
J 0
(1673 4750);
DISPLAY 0.872340 (1673 4750);
PAINT GREEN (1673 4750);
DISPLAY INVISIBLE (1673 4750);
FORCEADD TAP..1
(1850 4600);
FORCEPROP 3 LASTPIN (1800 4600) SIG_NAME M_F_CPU1_SA_DQS_DN<2>
J 0
(1810 4610);
DISPLAY 0.659574 (1810 4610);
PAINT MONO (1810 4610);
DISPLAY INVISIBLE (1810 4610);
FORCEPROP 1 LASTPIN (1800 4600) BN 2
J 0
(1788 4608);
DISPLAY 0.680851 (1788 4608);
PAINT GREEN (1788 4608);
FORCEPROP 2 LAST CDS_LIB standard
J 0
(1850 4600);
DISPLAY INVISIBLE (1850 4600);
FORCEPROP 1 LAST BODY_TYPE PLUMBING
J 0
(1850 4650);
DISPLAY 0.872340 (1850 4650);
PAINT GREEN (1850 4650);
DISPLAY INVISIBLE (1850 4650);
FORCEPROP 1 LAST HDL_TAP TRUE
J 0
(2175 4475);
DISPLAY 0.872340 (2175 4475);
DISPLAY INVISIBLE (2175 4475);
FORCEPROP 1 LAST PATH I152
J 0
(1848 4600);
DISPLAY 0.872340 (1848 4600);
PAINT GREEN (1848 4600);
DISPLAY INVISIBLE (1848 4600);
FORCEADD TAP..1
(1850 4700);
FORCEPROP 3 LASTPIN (1800 4700) SIG_NAME M_F_CPU1_SA_DQS_DN<3>
J 0
(1810 4710);
DISPLAY 0.659574 (1810 4710);
PAINT MONO (1810 4710);
DISPLAY INVISIBLE (1810 4710);
FORCEPROP 1 LASTPIN (1800 4700) BN 3
J 0
(1788 4708);
DISPLAY 0.680851 (1788 4708);
PAINT GREEN (1788 4708);
FORCEPROP 2 LAST CDS_LIB standard
J 0
(1850 4700);
PAINT MONO (1850 4700);
DISPLAY INVISIBLE (1850 4700);
FORCEPROP 1 LAST BODY_TYPE PLUMBING
J 0
(1850 4750);
DISPLAY 0.872340 (1850 4750);
PAINT GREEN (1850 4750);
DISPLAY INVISIBLE (1850 4750);
FORCEPROP 1 LAST HDL_TAP TRUE
J 0
(2175 4575);
DISPLAY 0.872340 (2175 4575);
DISPLAY INVISIBLE (2175 4575);
FORCEPROP 1 LAST PATH I153
J 0
(1848 4700);
DISPLAY 0.872340 (1848 4700);
PAINT GREEN (1848 4700);
DISPLAY INVISIBLE (1848 4700);
FORCEADD TAP..1
(1675 4850);
FORCEPROP 3 LASTPIN (1625 4850) SIG_NAME M_F_CPU1_SA_DQS_DP<4>
J 0
(1635 4860);
DISPLAY 0.659574 (1635 4860);
PAINT MONO (1635 4860);
DISPLAY INVISIBLE (1635 4860);
FORCEPROP 1 LASTPIN (1625 4850) BN 4
J 0
(1613 4858);
DISPLAY 0.680851 (1613 4858);
PAINT GREEN (1613 4858);
FORCEPROP 2 LAST CDS_LIB standard
J 0
(1675 4850);
PAINT MONO (1675 4850);
DISPLAY INVISIBLE (1675 4850);
FORCEPROP 1 LAST BODY_TYPE PLUMBING
J 0
(1675 4900);
DISPLAY 0.872340 (1675 4900);
PAINT GREEN (1675 4900);
DISPLAY INVISIBLE (1675 4900);
FORCEPROP 1 LAST HDL_TAP TRUE
J 0
(2000 4725);
DISPLAY 0.872340 (2000 4725);
DISPLAY INVISIBLE (2000 4725);
FORCEPROP 1 LAST PATH I154
J 0
(1673 4850);
DISPLAY 0.872340 (1673 4850);
PAINT GREEN (1673 4850);
DISPLAY INVISIBLE (1673 4850);
FORCEADD TAP..1
(1675 4950);
FORCEPROP 3 LASTPIN (1625 4950) SIG_NAME M_F_CPU1_SA_DQS_DP<5>
J 0
(1635 4960);
DISPLAY 0.659574 (1635 4960);
PAINT MONO (1635 4960);
DISPLAY INVISIBLE (1635 4960);
FORCEPROP 1 LASTPIN (1625 4950) BN 5
J 0
(1613 4958);
DISPLAY 0.680851 (1613 4958);
PAINT GREEN (1613 4958);
FORCEPROP 2 LAST CDS_LIB standard
J 0
(1675 4950);
DISPLAY INVISIBLE (1675 4950);
FORCEPROP 1 LAST BODY_TYPE PLUMBING
J 0
(1675 5000);
DISPLAY 0.872340 (1675 5000);
PAINT GREEN (1675 5000);
DISPLAY INVISIBLE (1675 5000);
FORCEPROP 1 LAST HDL_TAP TRUE
J 0
(2000 4825);
DISPLAY 0.872340 (2000 4825);
DISPLAY INVISIBLE (2000 4825);
FORCEPROP 1 LAST PATH I155
J 0
(1673 4950);
DISPLAY 0.872340 (1673 4950);
PAINT GREEN (1673 4950);
DISPLAY INVISIBLE (1673 4950);
FORCEADD TAP..1
(1850 4900);
FORCEPROP 3 LASTPIN (1800 4900) SIG_NAME M_F_CPU1_SA_DQS_DN<5>
J 0
(1810 4910);
DISPLAY 0.659574 (1810 4910);
PAINT MONO (1810 4910);
DISPLAY INVISIBLE (1810 4910);
FORCEPROP 1 LASTPIN (1800 4900) BN 5
J 0
(1788 4908);
DISPLAY 0.680851 (1788 4908);
PAINT GREEN (1788 4908);
FORCEPROP 2 LAST CDS_LIB standard
J 0
(1850 4900);
DISPLAY INVISIBLE (1850 4900);
FORCEPROP 1 LAST BODY_TYPE PLUMBING
J 0
(1850 4950);
DISPLAY 0.872340 (1850 4950);
PAINT GREEN (1850 4950);
DISPLAY INVISIBLE (1850 4950);
FORCEPROP 1 LAST HDL_TAP TRUE
J 0
(2175 4775);
DISPLAY 0.872340 (2175 4775);
DISPLAY INVISIBLE (2175 4775);
FORCEPROP 1 LAST PATH I156
J 0
(1848 4900);
DISPLAY 0.872340 (1848 4900);
PAINT GREEN (1848 4900);
DISPLAY INVISIBLE (1848 4900);
FORCEADD TAP..1
(1850 4800);
FORCEPROP 3 LASTPIN (1800 4800) SIG_NAME M_F_CPU1_SA_DQS_DN<4>
J 0
(1810 4810);
DISPLAY 0.659574 (1810 4810);
PAINT MONO (1810 4810);
DISPLAY INVISIBLE (1810 4810);
FORCEPROP 1 LASTPIN (1800 4800) BN 4
J 0
(1788 4808);
DISPLAY 0.680851 (1788 4808);
PAINT GREEN (1788 4808);
FORCEPROP 2 LAST CDS_LIB standard
J 0
(1850 4800);
PAINT MONO (1850 4800);
DISPLAY INVISIBLE (1850 4800);
FORCEPROP 1 LAST BODY_TYPE PLUMBING
J 0
(1850 4850);
DISPLAY 0.872340 (1850 4850);
PAINT GREEN (1850 4850);
DISPLAY INVISIBLE (1850 4850);
FORCEPROP 1 LAST HDL_TAP TRUE
J 0
(2175 4675);
DISPLAY 0.872340 (2175 4675);
DISPLAY INVISIBLE (2175 4675);
FORCEPROP 1 LAST PATH I157
J 0
(1848 4800);
DISPLAY 0.872340 (1848 4800);
PAINT GREEN (1848 4800);
DISPLAY INVISIBLE (1848 4800);
FORCEADD TAP..1
(1850 5000);
FORCEPROP 3 LASTPIN (1800 5000) SIG_NAME M_F_CPU1_SA_DQS_DN<6>
J 0
(1810 5010);
DISPLAY 0.659574 (1810 5010);
PAINT MONO (1810 5010);
DISPLAY INVISIBLE (1810 5010);
FORCEPROP 1 LASTPIN (1800 5000) BN 6
J 0
(1788 5008);
DISPLAY 0.680851 (1788 5008);
PAINT GREEN (1788 5008);
FORCEPROP 2 LAST CDS_LIB standard
J 0
(1850 5000);
DISPLAY INVISIBLE (1850 5000);
FORCEPROP 1 LAST BODY_TYPE PLUMBING
J 0
(1850 5050);
DISPLAY 0.872340 (1850 5050);
PAINT GREEN (1850 5050);
DISPLAY INVISIBLE (1850 5050);
FORCEPROP 1 LAST HDL_TAP TRUE
J 0
(2175 4875);
DISPLAY 0.872340 (2175 4875);
DISPLAY INVISIBLE (2175 4875);
FORCEPROP 1 LAST PATH I158
J 0
(1848 5000);
DISPLAY 0.872340 (1848 5000);
PAINT GREEN (1848 5000);
DISPLAY INVISIBLE (1848 5000);
FORCEADD UNIVERSAL_GND..1
(2275 1100);
FORCEPROP 3 LASTPIN (2275 1150) SIG_NAME GND\g
J 0
(2285 1160);
DISPLAY 0.659574 (2285 1160);
PAINT MONO (2285 1160);
DISPLAY INVISIBLE (2285 1160);
FORCEPROP 1 LAST PATH I159
J 0
(2350 1100);
DISPLAY 0.872340 (2350 1100);
PAINT AQUA (2350 1100);
DISPLAY INVISIBLE (2350 1100);
FORCEPROP 1 LAST HDL_POWER GND
J 1
(2300 1025);
DISPLAY 0.872340 (2300 1025);
PAINT GREEN (2300 1025);
DISPLAY INVISIBLE (2300 1025);
FORCEPROP 2 LAST CDS_LIB logical_power
J 0
(2275 1100);
PAINT MONO (2275 1100);
DISPLAY INVISIBLE (2275 1100);
FORCEADD OFFPAGE..1
(-3650 4200);
FORCEPROP 2 LAST $XR0 56 
J 0
(-3871 4200);
DISPLAY 0.638298 (-3871 4200);
PAINT MONO (-3871 4200);
FORCEPROP 2 LAST CDS_LIB standard
J 0
(-3650 4200);
PAINT MONO (-3650 4200);
DISPLAY INVISIBLE (-3650 4200);
FORCEPROP 1 LAST OFFPAGE TRUE
J 0
(-3325 4075);
DISPLAY 0.872340 (-3325 4075);
DISPLAY INVISIBLE (-3325 4075);
FORCEPROP 1 LAST COMMENT_BODY TRUE
J 0
(-3525 4100);
DISPLAY 0.872340 (-3525 4100);
PAINT GREEN (-3525 4100);
DISPLAY INVISIBLE (-3525 4100);
FORCEPROP 2 LAST PATH I16
J 0
(-3600 4275);
DISPLAY 1.021277 (-3600 4275);
DISPLAY INVISIBLE (-3600 4275);
FORCEADD Q_CAP..1
(2275 1475);
FORCEPROP 1 LAST PART_NUMBER CH6103KEA00
J 0
(2325 1325);
DISPLAY 0.978723 (2325 1325);
DISPLAY INVISIBLE (2325 1325);
FORCEPROP 1 LAST VALUE 10UF
J 0
(2325 1525);
DISPLAY 0.978723 (2325 1525);
FORCEPROP 1 LAST PACK_TYPE C0805
J 0
(2325 1275);
DISPLAY 0.978723 (2325 1275);
FORCEPROP 1 LAST TOLERANCE 10%
J 0
(2325 1425);
DISPLAY 0.978723 (2325 1425);
FORCEPROP 1 LAST VOLTAGE 16V
J 0
(2325 1475);
DISPLAY 0.978723 (2325 1475);
FORCEPROP 1 LAST MATERIAL X6S
J 0
(2325 1375);
DISPLAY 0.978723 (2325 1375);
FORCEPROP 1 LAST $LOCATION C89
J 0
(2325 1575);
DISPLAY 0.978723 (2325 1575);
FORCEPROP 1 LASTPIN (2275 1575) $PN 1
J 0
(2285 1555);
DISPLAY 0.787234 (2285 1555);
FORCEPROP 1 LASTPIN (2275 1375) $PN 2
J 0
(2285 1355);
DISPLAY 0.787234 (2285 1355);
FORCEPROP 2 LAST CDS_LIB pure_quanta
J 0
(2275 1475);
PAINT MONO (2275 1475);
DISPLAY INVISIBLE (2275 1475);
FORCEPROP 1 LAST PATH I160
J 0
(2325 1625);
DISPLAY 0.978723 (2325 1625);
PAINT WHITE (2325 1625);
DISPLAY INVISIBLE (2325 1625);
FORCEPROP 1 LAST $LOCATION C89
J 0
(2325 1675);
DISPLAY 1.021277 (2325 1675);
DISPLAY INVISIBLE (2325 1675);
FORCEPROP 2 LAST CDS_LOCATION C89
J 0
(2325 1675);
DISPLAY 1.021277 (2325 1675);
DISPLAY INVISIBLE (2325 1675);
FORCEPROP 2 LAST $SEC 1
J 0
(2325 1675);
DISPLAY 0.680851 (2325 1675);
PAINT MONO (2325 1675);
DISPLAY INVISIBLE (2325 1675);
FORCEPROP 2 LAST CDS_SEC 1
J 0
(2325 1675);
DISPLAY 1.021277 (2325 1675);
DISPLAY INVISIBLE (2325 1675);
FORCEADD UNIVERSAL_GND..1
(3350 1650);
FORCEPROP 3 LASTPIN (3350 1700) SIG_NAME GND\g
J 0
(3360 1710);
DISPLAY 0.659574 (3360 1710);
PAINT MONO (3360 1710);
DISPLAY INVISIBLE (3360 1710);
FORCEPROP 1 LAST PATH I161
J 0
(3425 1650);
DISPLAY 0.872340 (3425 1650);
PAINT AQUA (3425 1650);
DISPLAY INVISIBLE (3425 1650);
FORCEPROP 1 LAST HDL_POWER GND
J 1
(3375 1575);
DISPLAY 0.872340 (3375 1575);
PAINT GREEN (3375 1575);
DISPLAY INVISIBLE (3375 1575);
FORCEPROP 2 LAST CDS_LIB logical_power
J 0
(3350 1650);
PAINT MONO (3350 1650);
DISPLAY INVISIBLE (3350 1650);
FORCEADD OFFPAGE..2
(2800 4275);
FORCEPROP 2 LAST $XR1 109 
J 0
(3079 4275);
DISPLAY 0.638298 (3079 4275);
PAINT MONO (3079 4275);
FORCEPROP 2 LAST $XR0 56 
J 0
(2989 4275);
DISPLAY 0.638298 (2989 4275);
PAINT MONO (2989 4275);
FORCEPROP 2 LAST CDS_LIB standard
J 0
(2800 4275);
PAINT MONO (2800 4275);
DISPLAY INVISIBLE (2800 4275);
FORCEPROP 1 LAST OFFPAGE TRUE
J 0
(3125 4150);
DISPLAY 1.170213 (3125 4150);
PAINT GREEN (3125 4150);
DISPLAY INVISIBLE (3125 4150);
FORCEPROP 1 LAST COMMENT_BODY TRUE
J 0
(2755 4180);
DISPLAY 1.170213 (2755 4180);
PAINT GREEN (2755 4180);
DISPLAY INVISIBLE (2755 4180);
FORCEPROP 2 LAST PATH I163
J 0
(2975 4350);
DISPLAY 1.021277 (2975 4350);
DISPLAY INVISIBLE (2975 4350);
FORCEADD OFFPAGE..2
(2800 4325);
FORCEPROP 2 LAST $XR1 109 
J 0
(3079 4325);
DISPLAY 0.638298 (3079 4325);
PAINT MONO (3079 4325);
FORCEPROP 2 LAST $XR0 56 
J 0
(2989 4325);
DISPLAY 0.638298 (2989 4325);
PAINT MONO (2989 4325);
FORCEPROP 2 LAST CDS_LIB standard
J 0
(2800 4325);
PAINT MONO (2800 4325);
DISPLAY INVISIBLE (2800 4325);
FORCEPROP 1 LAST OFFPAGE TRUE
J 0
(3125 4200);
DISPLAY 1.170213 (3125 4200);
PAINT GREEN (3125 4200);
DISPLAY INVISIBLE (3125 4200);
FORCEPROP 1 LAST COMMENT_BODY TRUE
J 0
(2755 4230);
DISPLAY 1.170213 (2755 4230);
PAINT GREEN (2755 4230);
DISPLAY INVISIBLE (2755 4230);
FORCEPROP 2 LAST PATH I164
J 0
(2975 4400);
DISPLAY 1.021277 (2975 4400);
DISPLAY INVISIBLE (2975 4400);
FORCEADD TAP..1
(1675 5150);
FORCEPROP 3 LASTPIN (1625 5150) SIG_NAME M_F_CPU1_SA_DQS_DP<7>
J 0
(1635 5160);
DISPLAY 0.659574 (1635 5160);
PAINT MONO (1635 5160);
DISPLAY INVISIBLE (1635 5160);
FORCEPROP 1 LASTPIN (1625 5150) BN 7
J 0
(1613 5158);
DISPLAY 0.680851 (1613 5158);
PAINT GREEN (1613 5158);
FORCEPROP 2 LAST CDS_LIB standard
J 0
(1675 5150);
DISPLAY INVISIBLE (1675 5150);
FORCEPROP 1 LAST BODY_TYPE PLUMBING
J 0
(1675 5200);
DISPLAY 0.872340 (1675 5200);
PAINT GREEN (1675 5200);
DISPLAY INVISIBLE (1675 5200);
FORCEPROP 1 LAST HDL_TAP TRUE
J 0
(2000 5025);
DISPLAY 0.872340 (2000 5025);
DISPLAY INVISIBLE (2000 5025);
FORCEPROP 1 LAST PATH I165
J 0
(1673 5150);
DISPLAY 0.872340 (1673 5150);
PAINT GREEN (1673 5150);
DISPLAY INVISIBLE (1673 5150);
FORCEADD TAP..1
(1675 5050);
FORCEPROP 3 LASTPIN (1625 5050) SIG_NAME M_F_CPU1_SA_DQS_DP<6>
J 0
(1635 5060);
DISPLAY 0.659574 (1635 5060);
PAINT MONO (1635 5060);
DISPLAY INVISIBLE (1635 5060);
FORCEPROP 1 LASTPIN (1625 5050) BN 6
J 0
(1613 5058);
DISPLAY 0.680851 (1613 5058);
PAINT GREEN (1613 5058);
FORCEPROP 2 LAST CDS_LIB standard
J 0
(1675 5050);
DISPLAY INVISIBLE (1675 5050);
FORCEPROP 1 LAST BODY_TYPE PLUMBING
J 0
(1675 5100);
DISPLAY 0.872340 (1675 5100);
PAINT GREEN (1675 5100);
DISPLAY INVISIBLE (1675 5100);
FORCEPROP 1 LAST HDL_TAP TRUE
J 0
(2000 4925);
DISPLAY 0.872340 (2000 4925);
DISPLAY INVISIBLE (2000 4925);
FORCEPROP 1 LAST PATH I166
J 0
(1673 5050);
DISPLAY 0.872340 (1673 5050);
PAINT GREEN (1673 5050);
DISPLAY INVISIBLE (1673 5050);
FORCEADD TAP..1
(1675 5250);
FORCEPROP 3 LASTPIN (1625 5250) SIG_NAME M_F_CPU1_SA_DQS_DP<8>
J 0
(1635 5260);
DISPLAY 0.659574 (1635 5260);
PAINT MONO (1635 5260);
DISPLAY INVISIBLE (1635 5260);
FORCEPROP 1 LASTPIN (1625 5250) BN 8
J 0
(1613 5258);
DISPLAY 0.680851 (1613 5258);
PAINT GREEN (1613 5258);
FORCEPROP 2 LAST CDS_LIB standard
J 0
(1675 5250);
DISPLAY INVISIBLE (1675 5250);
FORCEPROP 1 LAST BODY_TYPE PLUMBING
J 0
(1675 5300);
DISPLAY 0.872340 (1675 5300);
PAINT GREEN (1675 5300);
DISPLAY INVISIBLE (1675 5300);
FORCEPROP 1 LAST HDL_TAP TRUE
J 0
(2000 5125);
DISPLAY 0.872340 (2000 5125);
DISPLAY INVISIBLE (2000 5125);
FORCEPROP 1 LAST PATH I167
J 0
(1673 5250);
DISPLAY 0.872340 (1673 5250);
PAINT GREEN (1673 5250);
DISPLAY INVISIBLE (1673 5250);
FORCEADD TAP..1
(1850 5100);
FORCEPROP 3 LASTPIN (1800 5100) SIG_NAME M_F_CPU1_SA_DQS_DN<7>
J 0
(1810 5110);
DISPLAY 0.659574 (1810 5110);
PAINT MONO (1810 5110);
DISPLAY INVISIBLE (1810 5110);
FORCEPROP 1 LASTPIN (1800 5100) BN 7
J 0
(1788 5108);
DISPLAY 0.680851 (1788 5108);
PAINT GREEN (1788 5108);
FORCEPROP 2 LAST CDS_LIB standard
J 0
(1850 5100);
DISPLAY INVISIBLE (1850 5100);
FORCEPROP 1 LAST BODY_TYPE PLUMBING
J 0
(1850 5150);
DISPLAY 0.872340 (1850 5150);
PAINT GREEN (1850 5150);
DISPLAY INVISIBLE (1850 5150);
FORCEPROP 1 LAST HDL_TAP TRUE
J 0
(2175 4975);
DISPLAY 0.872340 (2175 4975);
DISPLAY INVISIBLE (2175 4975);
FORCEPROP 1 LAST PATH I168
J 0
(1848 5100);
DISPLAY 0.872340 (1848 5100);
PAINT GREEN (1848 5100);
DISPLAY INVISIBLE (1848 5100);
FORCEADD TAP..1
(1850 5200);
FORCEPROP 3 LASTPIN (1800 5200) SIG_NAME M_F_CPU1_SA_DQS_DN<8>
J 0
(1810 5210);
DISPLAY 0.659574 (1810 5210);
PAINT MONO (1810 5210);
DISPLAY INVISIBLE (1810 5210);
FORCEPROP 1 LASTPIN (1800 5200) BN 8
J 0
(1788 5208);
DISPLAY 0.680851 (1788 5208);
PAINT GREEN (1788 5208);
FORCEPROP 2 LAST CDS_LIB standard
J 0
(1850 5200);
DISPLAY INVISIBLE (1850 5200);
FORCEPROP 1 LAST BODY_TYPE PLUMBING
J 0
(1850 5250);
DISPLAY 0.872340 (1850 5250);
PAINT GREEN (1850 5250);
DISPLAY INVISIBLE (1850 5250);
FORCEPROP 1 LAST HDL_TAP TRUE
J 0
(2175 5075);
DISPLAY 0.872340 (2175 5075);
DISPLAY INVISIBLE (2175 5075);
FORCEPROP 1 LAST PATH I169
J 0
(1848 5200);
DISPLAY 0.872340 (1848 5200);
PAINT GREEN (1848 5200);
DISPLAY INVISIBLE (1848 5200);
FORCEADD OFFPAGE..1
(-3650 4250);
FORCEPROP 2 LAST $XR0 56 
J 0
(-3871 4250);
DISPLAY 0.638298 (-3871 4250);
PAINT MONO (-3871 4250);
FORCEPROP 2 LAST CDS_LIB standard
J 0
(-3650 4250);
PAINT MONO (-3650 4250);
DISPLAY INVISIBLE (-3650 4250);
FORCEPROP 1 LAST OFFPAGE TRUE
J 0
(-3325 4125);
DISPLAY 0.872340 (-3325 4125);
DISPLAY INVISIBLE (-3325 4125);
FORCEPROP 1 LAST COMMENT_BODY TRUE
J 0
(-3525 4150);
DISPLAY 0.872340 (-3525 4150);
PAINT GREEN (-3525 4150);
DISPLAY INVISIBLE (-3525 4150);
FORCEPROP 2 LAST PATH I17
J 0
(-3600 4325);
DISPLAY 1.021277 (-3600 4325);
DISPLAY INVISIBLE (-3600 4325);
FORCEADD TAP..1
(1850 5300);
FORCEPROP 3 LASTPIN (1800 5300) SIG_NAME M_F_CPU1_SA_DQS_DN<9>
J 0
(1810 5310);
DISPLAY 0.659574 (1810 5310);
PAINT MONO (1810 5310);
DISPLAY INVISIBLE (1810 5310);
FORCEPROP 1 LASTPIN (1800 5300) BN 9
J 0
(1788 5308);
DISPLAY 0.680851 (1788 5308);
PAINT GREEN (1788 5308);
FORCEPROP 2 LAST CDS_LIB standard
J 0
(1850 5300);
DISPLAY INVISIBLE (1850 5300);
FORCEPROP 1 LAST BODY_TYPE PLUMBING
J 0
(1850 5350);
DISPLAY 0.872340 (1850 5350);
PAINT GREEN (1850 5350);
DISPLAY INVISIBLE (1850 5350);
FORCEPROP 1 LAST HDL_TAP TRUE
J 0
(2175 5175);
DISPLAY 0.872340 (2175 5175);
DISPLAY INVISIBLE (2175 5175);
FORCEPROP 1 LAST PATH I170
J 0
(1848 5300);
DISPLAY 0.872340 (1848 5300);
PAINT GREEN (1848 5300);
DISPLAY INVISIBLE (1848 5300);
FORCEADD TAP..1
(1675 5350);
FORCEPROP 3 LASTPIN (1625 5350) SIG_NAME M_F_CPU1_SA_DQS_DP<9>
J 0
(1635 5360);
DISPLAY 0.659574 (1635 5360);
PAINT MONO (1635 5360);
DISPLAY INVISIBLE (1635 5360);
FORCEPROP 1 LASTPIN (1625 5350) BN 9
J 0
(1613 5358);
DISPLAY 0.680851 (1613 5358);
PAINT GREEN (1613 5358);
FORCEPROP 2 LAST CDS_LIB standard
J 0
(1675 5350);
DISPLAY INVISIBLE (1675 5350);
FORCEPROP 1 LAST BODY_TYPE PLUMBING
J 0
(1675 5400);
DISPLAY 0.872340 (1675 5400);
PAINT GREEN (1675 5400);
DISPLAY INVISIBLE (1675 5400);
FORCEPROP 1 LAST HDL_TAP TRUE
J 0
(2000 5225);
DISPLAY 0.872340 (2000 5225);
DISPLAY INVISIBLE (2000 5225);
FORCEPROP 1 LAST PATH I171
J 0
(1673 5350);
DISPLAY 0.872340 (1673 5350);
PAINT GREEN (1673 5350);
DISPLAY INVISIBLE (1673 5350);
FORCEADD OFFPAGE..2
(2800 5325);
FORCEPROP 2 LAST $XR1 109 
J 0
(3079 5325);
DISPLAY 0.638298 (3079 5325);
PAINT MONO (3079 5325);
FORCEPROP 2 LAST $XR0 56 
J 0
(2989 5325);
DISPLAY 0.638298 (2989 5325);
PAINT MONO (2989 5325);
FORCEPROP 2 LAST CDS_LIB standard
J 0
(2800 5325);
PAINT MONO (2800 5325);
DISPLAY INVISIBLE (2800 5325);
FORCEPROP 1 LAST OFFPAGE TRUE
J 0
(3125 5200);
DISPLAY 1.170213 (3125 5200);
PAINT GREEN (3125 5200);
DISPLAY INVISIBLE (3125 5200);
FORCEPROP 1 LAST COMMENT_BODY TRUE
J 0
(2755 5230);
DISPLAY 1.170213 (2755 5230);
PAINT GREEN (2755 5230);
DISPLAY INVISIBLE (2755 5230);
FORCEPROP 2 LAST PATH I172
J 0
(2975 5400);
DISPLAY 1.021277 (2975 5400);
DISPLAY INVISIBLE (2975 5400);
FORCEADD OFFPAGE..2
(2800 5375);
FORCEPROP 2 LAST $XR1 109 
J 0
(3079 5375);
DISPLAY 0.638298 (3079 5375);
PAINT MONO (3079 5375);
FORCEPROP 2 LAST $XR0 56 
J 0
(2989 5375);
DISPLAY 0.638298 (2989 5375);
PAINT MONO (2989 5375);
FORCEPROP 2 LAST CDS_LIB standard
J 0
(2800 5375);
PAINT MONO (2800 5375);
DISPLAY INVISIBLE (2800 5375);
FORCEPROP 1 LAST OFFPAGE TRUE
J 0
(3125 5250);
DISPLAY 1.170213 (3125 5250);
PAINT GREEN (3125 5250);
DISPLAY INVISIBLE (3125 5250);
FORCEPROP 1 LAST COMMENT_BODY TRUE
J 0
(2755 5280);
DISPLAY 1.170213 (2755 5280);
PAINT GREEN (2755 5280);
DISPLAY INVISIBLE (2755 5280);
FORCEPROP 2 LAST PATH I173
J 0
(2975 5450);
DISPLAY 1.021277 (2975 5450);
DISPLAY INVISIBLE (2975 5450);
FORCEADD VCC_CORE..1
(3350 5900);
FORCEPROP 3 LASTPIN (3350 5850) SIG_NAME P12V_S3_AUX_CPU1_NVDIMM\g
J 0
(3360 5860);
DISPLAY 0.659574 (3360 5860);
PAINT MONO (3360 5860);
DISPLAY INVISIBLE (3360 5860);
FORCEPROP 1 LAST HDL_POWER P12V_S3_AUX_CPU1_NVDIMM
J 1
(3350 5950);
DISPLAY 1.148936 (3350 5950);
PAINT GREEN (3350 5950);
FORCEPROP 2 LAST CDS_LIB logical_power
J 0
(3350 5900);
PAINT MONO (3350 5900);
DISPLAY INVISIBLE (3350 5900);
FORCEPROP 1 LAST PATH I174
J 0
(3400 5925);
DISPLAY 0.872340 (3400 5925);
PAINT AQUA (3400 5925);
DISPLAY INVISIBLE (3400 5925);
FORCEADD UNIVERSAL_GND..1
(5050 1650);
FORCEPROP 3 LASTPIN (5050 1700) SIG_NAME GND\g
J 0
(5060 1710);
DISPLAY 0.659574 (5060 1710);
PAINT MONO (5060 1710);
DISPLAY INVISIBLE (5060 1710);
FORCEPROP 1 LAST PATH I175
J 0
(5125 1650);
DISPLAY 0.872340 (5125 1650);
PAINT AQUA (5125 1650);
DISPLAY INVISIBLE (5125 1650);
FORCEPROP 1 LAST HDL_POWER GND
J 1
(5075 1575);
DISPLAY 0.872340 (5075 1575);
PAINT GREEN (5075 1575);
DISPLAY INVISIBLE (5075 1575);
FORCEPROP 2 LAST CDS_LIB logical_power
J 0
(5050 1650);
PAINT MONO (5050 1650);
DISPLAY INVISIBLE (5050 1650);
FORCEADD TAP..1
(-1075 2750);
FORCEPROP 3 LASTPIN (-1125 2750) SIG_NAME M_F_CPU1_SB_DQ<12>
J 0
(-1115 2760);
DISPLAY 0.659574 (-1115 2760);
PAINT MONO (-1115 2760);
DISPLAY INVISIBLE (-1115 2760);
FORCEPROP 1 LASTPIN (-1125 2750) BN 12
J 0
(-1137 2758);
DISPLAY 0.680851 (-1137 2758);
PAINT GREEN (-1137 2758);
FORCEPROP 2 LAST CDS_LIB standard
J 0
(-1075 2750);
PAINT MONO (-1075 2750);
DISPLAY INVISIBLE (-1075 2750);
FORCEPROP 1 LAST BODY_TYPE PLUMBING
J 0
(-1075 2800);
DISPLAY 0.872340 (-1075 2800);
PAINT GREEN (-1075 2800);
DISPLAY INVISIBLE (-1075 2800);
FORCEPROP 1 LAST HDL_TAP TRUE
J 0
(-750 2625);
DISPLAY 0.872340 (-750 2625);
DISPLAY INVISIBLE (-750 2625);
FORCEPROP 1 LAST PATH I176
J 0
(-1077 2750);
DISPLAY 0.872340 (-1077 2750);
PAINT GREEN (-1077 2750);
DISPLAY INVISIBLE (-1077 2750);
FORCEADD SCONN288_ADR50017P130CC..3
(4200 3725);
FORCEPROP 1 LAST PART_NUMBER DFHST8FS461
J 0
(3745 5649);
DISPLAY 0.723404 (3745 5649);
PAINT GREEN (3745 5649);
DISPLAY INVISIBLE (3745 5649);
FORCEPROP 1 LAST MATERIAL IO
J 0
(3745 5522);
DISPLAY 0.723404 (3745 5522);
PAINT GREEN (3745 5522);
FORCEPROP 2 LAST PART_TYPE SMLF
J 0
(3750 5800);
DISPLAY 1.021277 (3750 5800);
FORCEPROP 2 LAST VALUE SCONN288_ADR50017-P130CC
J 0
(3750 5750);
DISPLAY 1.021277 (3750 5750);
FORCEPROP 1 LAST $LOCATION J27
J 0
(3750 5700);
DISPLAY 0.723404 (3750 5700);
PAINT GREEN (3750 5700);
FORCEPROP 0 LASTPIN (4800 2100) $PN G1
J 0
(4810 2110);
DISPLAY 0.680851 (4810 2110);
PAINT MONO (4810 2110);
FORCEPROP 0 LASTPIN (4800 2050) $PN G2
J 0
(4810 2060);
DISPLAY 0.680851 (4810 2060);
PAINT MONO (4810 2060);
FORCEPROP 0 LASTPIN (4800 2000) $PN G3
J 0
(4810 2010);
DISPLAY 0.680851 (4810 2010);
PAINT MONO (4810 2010);
FORCEPROP 0 LASTPIN (3600 5250) $PN 1
J 2
(3590 5260);
DISPLAY 0.680851 (3590 5260);
PAINT MONO (3590 5260);
FORCEPROP 0 LASTPIN (3600 5300) $PN 145
J 2
(3590 5310);
DISPLAY 0.680851 (3590 5310);
PAINT MONO (3590 5310);
FORCEPROP 0 LASTPIN (3600 5350) $PN 146
J 2
(3590 5360);
DISPLAY 0.680851 (3590 5360);
PAINT MONO (3590 5360);
FORCEPROP 0 LASTPIN (4800 2200) $PN 6
J 0
(4810 2210);
DISPLAY 0.680851 (4810 2210);
PAINT MONO (4810 2210);
FORCEPROP 0 LASTPIN (4800 2250) $PN 8
J 0
(4810 2260);
DISPLAY 0.680851 (4810 2260);
PAINT MONO (4810 2260);
FORCEPROP 0 LASTPIN (4800 2300) $PN 10
J 0
(4810 2310);
DISPLAY 0.680851 (4810 2310);
PAINT MONO (4810 2310);
FORCEPROP 0 LASTPIN (4800 2350) $PN 13
J 0
(4810 2360);
DISPLAY 0.680851 (4810 2360);
PAINT MONO (4810 2360);
FORCEPROP 0 LASTPIN (4800 2400) $PN 15
J 0
(4810 2410);
DISPLAY 0.680851 (4810 2410);
PAINT MONO (4810 2410);
FORCEPROP 0 LASTPIN (4800 2450) $PN 17
J 0
(4810 2460);
DISPLAY 0.680851 (4810 2460);
PAINT MONO (4810 2460);
FORCEPROP 0 LASTPIN (4800 2500) $PN 19
J 0
(4810 2510);
DISPLAY 0.680851 (4810 2510);
PAINT MONO (4810 2510);
FORCEPROP 0 LASTPIN (4800 2550) $PN 21
J 0
(4810 2560);
DISPLAY 0.680851 (4810 2560);
PAINT MONO (4810 2560);
FORCEPROP 0 LASTPIN (4800 2600) $PN 24
J 0
(4810 2610);
DISPLAY 0.680851 (4810 2610);
PAINT MONO (4810 2610);
FORCEPROP 0 LASTPIN (4800 2650) $PN 26
J 0
(4810 2660);
DISPLAY 0.680851 (4810 2660);
PAINT MONO (4810 2660);
FORCEPROP 0 LASTPIN (4800 2700) $PN 28
J 0
(4810 2710);
DISPLAY 0.680851 (4810 2710);
PAINT MONO (4810 2710);
FORCEPROP 0 LASTPIN (4800 2750) $PN 30
J 0
(4810 2760);
DISPLAY 0.680851 (4810 2760);
PAINT MONO (4810 2760);
FORCEPROP 0 LASTPIN (4800 2800) $PN 32
J 0
(4810 2810);
DISPLAY 0.680851 (4810 2810);
PAINT MONO (4810 2810);
FORCEPROP 0 LASTPIN (4800 2850) $PN 35
J 0
(4810 2860);
DISPLAY 0.680851 (4810 2860);
PAINT MONO (4810 2860);
FORCEPROP 0 LASTPIN (4800 2900) $PN 37
J 0
(4810 2910);
DISPLAY 0.680851 (4810 2910);
PAINT MONO (4810 2910);
FORCEPROP 0 LASTPIN (4800 2950) $PN 39
J 0
(4810 2960);
DISPLAY 0.680851 (4810 2960);
PAINT MONO (4810 2960);
FORCEPROP 0 LASTPIN (4800 3000) $PN 41
J 0
(4810 3010);
DISPLAY 0.680851 (4810 3010);
PAINT MONO (4810 3010);
FORCEPROP 0 LASTPIN (4800 3050) $PN 43
J 0
(4810 3060);
DISPLAY 0.680851 (4810 3060);
PAINT MONO (4810 3060);
FORCEPROP 0 LASTPIN (4800 3100) $PN 46
J 0
(4810 3110);
DISPLAY 0.680851 (4810 3110);
PAINT MONO (4810 3110);
FORCEPROP 0 LASTPIN (4800 3150) $PN 48
J 0
(4810 3160);
DISPLAY 0.680851 (4810 3160);
PAINT MONO (4810 3160);
FORCEPROP 0 LASTPIN (4800 3200) $PN 50
J 0
(4810 3210);
DISPLAY 0.680851 (4810 3210);
PAINT MONO (4810 3210);
FORCEPROP 0 LASTPIN (4800 3250) $PN 52
J 0
(4810 3260);
DISPLAY 0.680851 (4810 3260);
PAINT MONO (4810 3260);
FORCEPROP 0 LASTPIN (4800 3300) $PN 54
J 0
(4810 3310);
DISPLAY 0.680851 (4810 3310);
PAINT MONO (4810 3310);
FORCEPROP 0 LASTPIN (4800 3350) $PN 57
J 0
(4810 3360);
DISPLAY 0.680851 (4810 3360);
PAINT MONO (4810 3360);
FORCEPROP 0 LASTPIN (4800 3400) $PN 59
J 0
(4810 3410);
DISPLAY 0.680851 (4810 3410);
PAINT MONO (4810 3410);
FORCEPROP 0 LASTPIN (4800 3450) $PN 61
J 0
(4810 3460);
DISPLAY 0.680851 (4810 3460);
PAINT MONO (4810 3460);
FORCEPROP 0 LASTPIN (4800 3500) $PN 63
J 0
(4810 3510);
DISPLAY 0.680851 (4810 3510);
PAINT MONO (4810 3510);
FORCEPROP 0 LASTPIN (4800 3550) $PN 65
J 0
(4810 3560);
DISPLAY 0.680851 (4810 3560);
PAINT MONO (4810 3560);
FORCEPROP 0 LASTPIN (4800 3600) $PN 67
J 0
(4810 3610);
DISPLAY 0.680851 (4810 3610);
PAINT MONO (4810 3610);
FORCEPROP 0 LASTPIN (4800 3650) $PN 69
J 0
(4810 3660);
DISPLAY 0.680851 (4810 3660);
PAINT MONO (4810 3660);
FORCEPROP 0 LASTPIN (4800 3700) $PN 71
J 0
(4810 3710);
DISPLAY 0.680851 (4810 3710);
PAINT MONO (4810 3710);
FORCEPROP 0 LASTPIN (4800 3750) $PN 73
J 0
(4810 3760);
DISPLAY 0.680851 (4810 3760);
PAINT MONO (4810 3760);
FORCEPROP 0 LASTPIN (4800 3800) $PN 75
J 0
(4810 3810);
DISPLAY 0.680851 (4810 3810);
PAINT MONO (4810 3810);
FORCEPROP 0 LASTPIN (4800 3850) $PN 77
J 0
(4810 3860);
DISPLAY 0.680851 (4810 3860);
PAINT MONO (4810 3860);
FORCEPROP 0 LASTPIN (4800 3900) $PN 79
J 0
(4810 3910);
DISPLAY 0.680851 (4810 3910);
PAINT MONO (4810 3910);
FORCEPROP 0 LASTPIN (4800 3950) $PN 81
J 0
(4810 3960);
DISPLAY 0.680851 (4810 3960);
PAINT MONO (4810 3960);
FORCEPROP 0 LASTPIN (4800 4000) $PN 83
J 0
(4810 4010);
DISPLAY 0.680851 (4810 4010);
PAINT MONO (4810 4010);
FORCEPROP 0 LASTPIN (4800 4050) $PN 85
J 0
(4810 4060);
DISPLAY 0.680851 (4810 4060);
PAINT MONO (4810 4060);
FORCEPROP 0 LASTPIN (4800 4100) $PN 88
J 0
(4810 4110);
DISPLAY 0.680851 (4810 4110);
PAINT MONO (4810 4110);
FORCEPROP 0 LASTPIN (4800 4150) $PN 90
J 0
(4810 4160);
DISPLAY 0.680851 (4810 4160);
PAINT MONO (4810 4160);
FORCEPROP 0 LASTPIN (4800 4200) $PN 92
J 0
(4810 4210);
DISPLAY 0.680851 (4810 4210);
PAINT MONO (4810 4210);
FORCEPROP 0 LASTPIN (4800 4250) $PN 95
J 0
(4810 4260);
DISPLAY 0.680851 (4810 4260);
PAINT MONO (4810 4260);
FORCEPROP 0 LASTPIN (4800 4300) $PN 97
J 0
(4810 4310);
DISPLAY 0.680851 (4810 4310);
PAINT MONO (4810 4310);
FORCEPROP 0 LASTPIN (4800 4350) $PN 99
J 0
(4810 4360);
DISPLAY 0.680851 (4810 4360);
PAINT MONO (4810 4360);
FORCEPROP 0 LASTPIN (4800 4400) $PN 101
J 0
(4810 4410);
DISPLAY 0.680851 (4810 4410);
PAINT MONO (4810 4410);
FORCEPROP 0 LASTPIN (4800 4450) $PN 103
J 0
(4810 4460);
DISPLAY 0.680851 (4810 4460);
PAINT MONO (4810 4460);
FORCEPROP 0 LASTPIN (4800 4500) $PN 106
J 0
(4810 4510);
DISPLAY 0.680851 (4810 4510);
PAINT MONO (4810 4510);
FORCEPROP 0 LASTPIN (4800 4550) $PN 108
J 0
(4810 4560);
DISPLAY 0.680851 (4810 4560);
PAINT MONO (4810 4560);
FORCEPROP 0 LASTPIN (4800 4600) $PN 110
J 0
(4810 4610);
DISPLAY 0.680851 (4810 4610);
PAINT MONO (4810 4610);
FORCEPROP 0 LASTPIN (4800 4650) $PN 112
J 0
(4810 4660);
DISPLAY 0.680851 (4810 4660);
PAINT MONO (4810 4660);
FORCEPROP 0 LASTPIN (4800 4700) $PN 114
J 0
(4810 4710);
DISPLAY 0.680851 (4810 4710);
PAINT MONO (4810 4710);
FORCEPROP 0 LASTPIN (4800 4750) $PN 117
J 0
(4810 4760);
DISPLAY 0.680851 (4810 4760);
PAINT MONO (4810 4760);
FORCEPROP 0 LASTPIN (4800 4800) $PN 119
J 0
(4810 4810);
DISPLAY 0.680851 (4810 4810);
PAINT MONO (4810 4810);
FORCEPROP 0 LASTPIN (4800 4850) $PN 121
J 0
(4810 4860);
DISPLAY 0.680851 (4810 4860);
PAINT MONO (4810 4860);
FORCEPROP 0 LASTPIN (4800 4900) $PN 123
J 0
(4810 4910);
DISPLAY 0.680851 (4810 4910);
PAINT MONO (4810 4910);
FORCEPROP 0 LASTPIN (4800 4950) $PN 125
J 0
(4810 4960);
DISPLAY 0.680851 (4810 4960);
PAINT MONO (4810 4960);
FORCEPROP 0 LASTPIN (4800 5000) $PN 128
J 0
(4810 5010);
DISPLAY 0.680851 (4810 5010);
PAINT MONO (4810 5010);
FORCEPROP 0 LASTPIN (4800 5050) $PN 130
J 0
(4810 5060);
DISPLAY 0.680851 (4810 5060);
PAINT MONO (4810 5060);
FORCEPROP 0 LASTPIN (4800 5100) $PN 132
J 0
(4810 5110);
DISPLAY 0.680851 (4810 5110);
PAINT MONO (4810 5110);
FORCEPROP 0 LASTPIN (4800 5150) $PN 134
J 0
(4810 5160);
DISPLAY 0.680851 (4810 5160);
PAINT MONO (4810 5160);
FORCEPROP 0 LASTPIN (4800 5200) $PN 136
J 0
(4810 5210);
DISPLAY 0.680851 (4810 5210);
PAINT MONO (4810 5210);
FORCEPROP 0 LASTPIN (4800 5250) $PN 139
J 0
(4810 5260);
DISPLAY 0.680851 (4810 5260);
PAINT MONO (4810 5260);
FORCEPROP 0 LASTPIN (4800 5300) $PN 141
J 0
(4810 5310);
DISPLAY 0.680851 (4810 5310);
PAINT MONO (4810 5310);
FORCEPROP 0 LASTPIN (4800 5350) $PN 143
J 0
(4810 5360);
DISPLAY 0.680851 (4810 5360);
PAINT MONO (4810 5360);
FORCEPROP 0 LASTPIN (3600 2100) $PN 151
J 2
(3590 2110);
DISPLAY 0.680851 (3590 2110);
PAINT MONO (3590 2110);
FORCEPROP 0 LASTPIN (3600 2150) $PN 153
J 2
(3590 2160);
DISPLAY 0.680851 (3590 2160);
PAINT MONO (3590 2160);
FORCEPROP 0 LASTPIN (3600 2200) $PN 155
J 2
(3590 2210);
DISPLAY 0.680851 (3590 2210);
PAINT MONO (3590 2210);
FORCEPROP 0 LASTPIN (3600 2250) $PN 158
J 2
(3590 2260);
DISPLAY 0.680851 (3590 2260);
PAINT MONO (3590 2260);
FORCEPROP 0 LASTPIN (3600 2300) $PN 160
J 2
(3590 2310);
DISPLAY 0.680851 (3590 2310);
PAINT MONO (3590 2310);
FORCEPROP 0 LASTPIN (3600 2350) $PN 162
J 2
(3590 2360);
DISPLAY 0.680851 (3590 2360);
PAINT MONO (3590 2360);
FORCEPROP 0 LASTPIN (3600 2400) $PN 164
J 2
(3590 2410);
DISPLAY 0.680851 (3590 2410);
PAINT MONO (3590 2410);
FORCEPROP 0 LASTPIN (3600 2450) $PN 166
J 2
(3590 2460);
DISPLAY 0.680851 (3590 2460);
PAINT MONO (3590 2460);
FORCEPROP 0 LASTPIN (3600 2500) $PN 169
J 2
(3590 2510);
DISPLAY 0.680851 (3590 2510);
PAINT MONO (3590 2510);
FORCEPROP 0 LASTPIN (3600 2550) $PN 171
J 2
(3590 2560);
DISPLAY 0.680851 (3590 2560);
PAINT MONO (3590 2560);
FORCEPROP 0 LASTPIN (3600 2600) $PN 173
J 2
(3590 2610);
DISPLAY 0.680851 (3590 2610);
PAINT MONO (3590 2610);
FORCEPROP 0 LASTPIN (3600 2650) $PN 175
J 2
(3590 2660);
DISPLAY 0.680851 (3590 2660);
PAINT MONO (3590 2660);
FORCEPROP 0 LASTPIN (3600 2700) $PN 177
J 2
(3590 2710);
DISPLAY 0.680851 (3590 2710);
PAINT MONO (3590 2710);
FORCEPROP 0 LASTPIN (3600 2750) $PN 180
J 2
(3590 2760);
DISPLAY 0.680851 (3590 2760);
PAINT MONO (3590 2760);
FORCEPROP 0 LASTPIN (3600 2800) $PN 182
J 2
(3590 2810);
DISPLAY 0.680851 (3590 2810);
PAINT MONO (3590 2810);
FORCEPROP 0 LASTPIN (3600 2850) $PN 184
J 2
(3590 2860);
DISPLAY 0.680851 (3590 2860);
PAINT MONO (3590 2860);
FORCEPROP 0 LASTPIN (3600 2900) $PN 186
J 2
(3590 2910);
DISPLAY 0.680851 (3590 2910);
PAINT MONO (3590 2910);
FORCEPROP 0 LASTPIN (3600 2950) $PN 188
J 2
(3590 2960);
DISPLAY 0.680851 (3590 2960);
PAINT MONO (3590 2960);
FORCEPROP 0 LASTPIN (3600 3000) $PN 191
J 2
(3590 3010);
DISPLAY 0.680851 (3590 3010);
PAINT MONO (3590 3010);
FORCEPROP 0 LASTPIN (3600 3050) $PN 193
J 2
(3590 3060);
DISPLAY 0.680851 (3590 3060);
PAINT MONO (3590 3060);
FORCEPROP 0 LASTPIN (3600 3100) $PN 195
J 2
(3590 3110);
DISPLAY 0.680851 (3590 3110);
PAINT MONO (3590 3110);
FORCEPROP 0 LASTPIN (3600 3150) $PN 197
J 2
(3590 3160);
DISPLAY 0.680851 (3590 3160);
PAINT MONO (3590 3160);
FORCEPROP 0 LASTPIN (3600 3200) $PN 199
J 2
(3590 3210);
DISPLAY 0.680851 (3590 3210);
PAINT MONO (3590 3210);
FORCEPROP 0 LASTPIN (3600 3250) $PN 202
J 2
(3590 3260);
DISPLAY 0.680851 (3590 3260);
PAINT MONO (3590 3260);
FORCEPROP 0 LASTPIN (3600 3300) $PN 204
J 2
(3590 3310);
DISPLAY 0.680851 (3590 3310);
PAINT MONO (3590 3310);
FORCEPROP 0 LASTPIN (3600 3350) $PN 206
J 2
(3590 3360);
DISPLAY 0.680851 (3590 3360);
PAINT MONO (3590 3360);
FORCEPROP 0 LASTPIN (3600 3400) $PN 208
J 2
(3590 3410);
DISPLAY 0.680851 (3590 3410);
PAINT MONO (3590 3410);
FORCEPROP 0 LASTPIN (3600 3450) $PN 210
J 2
(3590 3460);
DISPLAY 0.680851 (3590 3460);
PAINT MONO (3590 3460);
FORCEPROP 0 LASTPIN (3600 3500) $PN 212
J 2
(3590 3510);
DISPLAY 0.680851 (3590 3510);
PAINT MONO (3590 3510);
FORCEPROP 0 LASTPIN (3600 3550) $PN 214
J 2
(3590 3560);
DISPLAY 0.680851 (3590 3560);
PAINT MONO (3590 3560);
FORCEPROP 0 LASTPIN (3600 3600) $PN 216
J 2
(3590 3610);
DISPLAY 0.680851 (3590 3610);
PAINT MONO (3590 3610);
FORCEPROP 0 LASTPIN (3600 3650) $PN 219
J 2
(3590 3660);
DISPLAY 0.680851 (3590 3660);
PAINT MONO (3590 3660);
FORCEPROP 0 LASTPIN (3600 3700) $PN 222
J 2
(3590 3710);
DISPLAY 0.680851 (3590 3710);
PAINT MONO (3590 3710);
FORCEPROP 0 LASTPIN (3600 3750) $PN 224
J 2
(3590 3760);
DISPLAY 0.680851 (3590 3760);
PAINT MONO (3590 3760);
FORCEPROP 0 LASTPIN (3600 3800) $PN 226
J 2
(3590 3810);
DISPLAY 0.680851 (3590 3810);
PAINT MONO (3590 3810);
FORCEPROP 0 LASTPIN (3600 3850) $PN 228
J 2
(3590 3860);
DISPLAY 0.680851 (3590 3860);
PAINT MONO (3590 3860);
FORCEPROP 0 LASTPIN (3600 3900) $PN 230
J 2
(3590 3910);
DISPLAY 0.680851 (3590 3910);
PAINT MONO (3590 3910);
FORCEPROP 0 LASTPIN (3600 3950) $PN 233
J 2
(3590 3960);
DISPLAY 0.680851 (3590 3960);
PAINT MONO (3590 3960);
FORCEPROP 0 LASTPIN (3600 4000) $PN 235
J 2
(3590 4010);
DISPLAY 0.680851 (3590 4010);
PAINT MONO (3590 4010);
FORCEPROP 0 LASTPIN (3600 4050) $PN 237
J 2
(3590 4060);
DISPLAY 0.680851 (3590 4060);
PAINT MONO (3590 4060);
FORCEPROP 0 LASTPIN (3600 4100) $PN 240
J 2
(3590 4110);
DISPLAY 0.680851 (3590 4110);
PAINT MONO (3590 4110);
FORCEPROP 0 LASTPIN (3600 4150) $PN 242
J 2
(3590 4160);
DISPLAY 0.680851 (3590 4160);
PAINT MONO (3590 4160);
FORCEPROP 0 LASTPIN (3600 4200) $PN 244
J 2
(3590 4210);
DISPLAY 0.680851 (3590 4210);
PAINT MONO (3590 4210);
FORCEPROP 0 LASTPIN (3600 4250) $PN 246
J 2
(3590 4260);
DISPLAY 0.680851 (3590 4260);
PAINT MONO (3590 4260);
FORCEPROP 0 LASTPIN (3600 4300) $PN 248
J 2
(3590 4310);
DISPLAY 0.680851 (3590 4310);
PAINT MONO (3590 4310);
FORCEPROP 0 LASTPIN (3600 4350) $PN 251
J 2
(3590 4360);
DISPLAY 0.680851 (3590 4360);
PAINT MONO (3590 4360);
FORCEPROP 0 LASTPIN (3600 4400) $PN 253
J 2
(3590 4410);
DISPLAY 0.680851 (3590 4410);
PAINT MONO (3590 4410);
FORCEPROP 0 LASTPIN (3600 4450) $PN 255
J 2
(3590 4460);
DISPLAY 0.680851 (3590 4460);
PAINT MONO (3590 4460);
FORCEPROP 0 LASTPIN (3600 4500) $PN 257
J 2
(3590 4510);
DISPLAY 0.680851 (3590 4510);
PAINT MONO (3590 4510);
FORCEPROP 0 LASTPIN (3600 4550) $PN 259
J 2
(3590 4560);
DISPLAY 0.680851 (3590 4560);
PAINT MONO (3590 4560);
FORCEPROP 0 LASTPIN (3600 4600) $PN 262
J 2
(3590 4610);
DISPLAY 0.680851 (3590 4610);
PAINT MONO (3590 4610);
FORCEPROP 0 LASTPIN (3600 4650) $PN 264
J 2
(3590 4660);
DISPLAY 0.680851 (3590 4660);
PAINT MONO (3590 4660);
FORCEPROP 0 LASTPIN (3600 4700) $PN 266
J 2
(3590 4710);
DISPLAY 0.680851 (3590 4710);
PAINT MONO (3590 4710);
FORCEPROP 0 LASTPIN (3600 4750) $PN 268
J 2
(3590 4760);
DISPLAY 0.680851 (3590 4760);
PAINT MONO (3590 4760);
FORCEPROP 0 LASTPIN (3600 4800) $PN 270
J 2
(3590 4810);
DISPLAY 0.680851 (3590 4810);
PAINT MONO (3590 4810);
FORCEPROP 0 LASTPIN (3600 4850) $PN 273
J 2
(3590 4860);
DISPLAY 0.680851 (3590 4860);
PAINT MONO (3590 4860);
FORCEPROP 0 LASTPIN (3600 4900) $PN 275
J 2
(3590 4910);
DISPLAY 0.680851 (3590 4910);
PAINT MONO (3590 4910);
FORCEPROP 0 LASTPIN (3600 4950) $PN 277
J 2
(3590 4960);
DISPLAY 0.680851 (3590 4960);
PAINT MONO (3590 4960);
FORCEPROP 0 LASTPIN (3600 5000) $PN 279
J 2
(3590 5010);
DISPLAY 0.680851 (3590 5010);
PAINT MONO (3590 5010);
FORCEPROP 0 LASTPIN (3600 5050) $PN 281
J 2
(3590 5060);
DISPLAY 0.680851 (3590 5060);
PAINT MONO (3590 5060);
FORCEPROP 0 LASTPIN (3600 5100) $PN 284
J 2
(3590 5110);
DISPLAY 0.680851 (3590 5110);
PAINT MONO (3590 5110);
FORCEPROP 0 LASTPIN (3600 5150) $PN 286
J 2
(3590 5160);
DISPLAY 0.680851 (3590 5160);
PAINT MONO (3590 5160);
FORCEPROP 0 LASTPIN (3600 5200) $PN 288
J 2
(3590 5210);
DISPLAY 0.680851 (3590 5210);
PAINT MONO (3590 5210);
FORCEPROP 1 LAST NEEDS_NO_SIZE TRUE
J 0
(4200 3725);
DISPLAY 0.723404 (4200 3725);
PAINT GREEN (4200 3725);
DISPLAY INVISIBLE (4200 3725);
FORCEPROP 1 LAST CDS_LMAN_SYM_OUTLINE -450,1775,450,-1775
J 0
(4200 3725);
DISPLAY 0.468085 (4200 3725);
PAINT GREEN (4200 3725);
DISPLAY INVISIBLE (4200 3725);
FORCEPROP 2 LAST CDS_LIB pure_quanta
J 0
(4200 3725);
DISPLAY INVISIBLE (4200 3725);
FORCEPROP 1 LAST PATH I178
J 0
(4200 3725);
DISPLAY 0.723404 (4200 3725);
PAINT GREEN (4200 3725);
DISPLAY INVISIBLE (4200 3725);
FORCEPROP 2 LAST CDS_LOCATION J27
J 0
(3750 5850);
DISPLAY 1.021277 (3750 5850);
DISPLAY INVISIBLE (3750 5850);
FORCEPROP 0 LAST $SEC 3
J 0
(3750 5850);
DISPLAY 0.680851 (3750 5850);
PAINT MONO (3750 5850);
DISPLAY INVISIBLE (3750 5850);
FORCEPROP 2 LAST CDS_SEC 3
J 0
(3750 5850);
DISPLAY 1.021277 (3750 5850);
DISPLAY INVISIBLE (3750 5850);
FORCEADD SCONN288_ADR50017P130CC..1
(-1900 3625);
FORCEPROP 1 LAST PART_NUMBER DFHST8FS461
J 0
(-2345 5647);
DISPLAY 0.723404 (-2345 5647);
PAINT GREEN (-2345 5647);
DISPLAY INVISIBLE (-2345 5647);
FORCEPROP 1 LAST MATERIAL IO
J 0
(-2345 5520);
DISPLAY 0.723404 (-2345 5520);
PAINT GREEN (-2345 5520);
FORCEPROP 2 LAST PART_TYPE SMLF
J 0
(-2350 5800);
DISPLAY 1.021277 (-2350 5800);
FORCEPROP 2 LAST VALUE SCONN288_ADR50017-P130CC
J 0
(-2350 5750);
DISPLAY 1.021277 (-2350 5750);
FORCEPROP 1 LAST $LOCATION J27
J 0
(-2350 5700);
DISPLAY 0.723404 (-2350 5700);
PAINT GREEN (-2350 5700);
FORCEPROP 0 LASTPIN (-2500 3000) $PN 62
J 2
(-2510 3010);
DISPLAY 0.680851 (-2510 3010);
PAINT MONO (-2510 3010);
FORCEPROP 0 LASTPIN (-2500 5050) $PN 66
J 2
(-2510 5060);
DISPLAY 0.680851 (-2510 5060);
PAINT MONO (-2510 5060);
FORCEPROP 0 LASTPIN (-2500 4650) $PN 76
J 2
(-2510 4660);
DISPLAY 0.680851 (-2510 4660);
PAINT MONO (-2510 4660);
FORCEPROP 0 LASTPIN (-2500 5100) $PN 211
J 2
(-2510 5110);
DISPLAY 0.680851 (-2510 5110);
PAINT MONO (-2510 5110);
FORCEPROP 0 LASTPIN (-2500 4700) $PN 221
J 2
(-2510 4710);
DISPLAY 0.680851 (-2510 4710);
PAINT MONO (-2510 4710);
FORCEPROP 0 LASTPIN (-2500 5150) $PN 68
J 2
(-2510 5160);
DISPLAY 0.680851 (-2510 5160);
PAINT MONO (-2510 5160);
FORCEPROP 0 LASTPIN (-2500 4750) $PN 78
J 2
(-2510 4760);
DISPLAY 0.680851 (-2510 4760);
PAINT MONO (-2510 4760);
FORCEPROP 0 LASTPIN (-2500 5200) $PN 213
J 2
(-2510 5210);
DISPLAY 0.680851 (-2510 5210);
PAINT MONO (-2510 5210);
FORCEPROP 0 LASTPIN (-2500 4800) $PN 223
J 2
(-2510 4810);
DISPLAY 0.680851 (-2510 4810);
PAINT MONO (-2510 4810);
FORCEPROP 0 LASTPIN (-2500 5250) $PN 70
J 2
(-2510 5260);
DISPLAY 0.680851 (-2510 5260);
PAINT MONO (-2510 5260);
FORCEPROP 0 LASTPIN (-2500 4850) $PN 80
J 2
(-2510 4860);
DISPLAY 0.680851 (-2510 4860);
PAINT MONO (-2510 4860);
FORCEPROP 0 LASTPIN (-2500 5300) $PN 215
J 2
(-2510 5310);
DISPLAY 0.680851 (-2510 5310);
PAINT MONO (-2510 5310);
FORCEPROP 0 LASTPIN (-2500 4900) $PN 225
J 2
(-2510 4910);
DISPLAY 0.680851 (-2510 4910);
PAINT MONO (-2510 4910);
FORCEPROP 0 LASTPIN (-2500 5350) $PN 72
J 2
(-2510 5360);
DISPLAY 0.680851 (-2510 5360);
PAINT MONO (-2510 5360);
FORCEPROP 0 LASTPIN (-2500 4950) $PN 82
J 2
(-2510 4960);
DISPLAY 0.680851 (-2510 4960);
PAINT MONO (-2510 4960);
FORCEPROP 0 LASTPIN (-2500 3600) $PN 51
J 2
(-2510 3610);
DISPLAY 0.680851 (-2510 3610);
PAINT MONO (-2510 3610);
FORCEPROP 0 LASTPIN (-2500 3150) $PN 96
J 2
(-2510 3160);
DISPLAY 0.680851 (-2510 3160);
PAINT MONO (-2510 3160);
FORCEPROP 0 LASTPIN (-2500 3650) $PN 53
J 2
(-2510 3660);
DISPLAY 0.680851 (-2510 3660);
PAINT MONO (-2510 3660);
FORCEPROP 0 LASTPIN (-2500 3200) $PN 98
J 2
(-2510 3210);
DISPLAY 0.680851 (-2510 3210);
PAINT MONO (-2510 3210);
FORCEPROP 0 LASTPIN (-2500 3700) $PN 196
J 2
(-2510 3710);
DISPLAY 0.680851 (-2510 3710);
PAINT MONO (-2510 3710);
FORCEPROP 0 LASTPIN (-2500 3250) $PN 241
J 2
(-2510 3260);
DISPLAY 0.680851 (-2510 3260);
PAINT MONO (-2510 3260);
FORCEPROP 0 LASTPIN (-2500 3750) $PN 198
J 2
(-2510 3760);
DISPLAY 0.680851 (-2510 3760);
PAINT MONO (-2510 3760);
FORCEPROP 0 LASTPIN (-2500 3300) $PN 243
J 2
(-2510 3310);
DISPLAY 0.680851 (-2510 3310);
PAINT MONO (-2510 3310);
FORCEPROP 0 LASTPIN (-2500 3800) $PN 58
J 2
(-2510 3810);
DISPLAY 0.680851 (-2510 3810);
PAINT MONO (-2510 3810);
FORCEPROP 0 LASTPIN (-2500 3350) $PN 89
J 2
(-2510 3360);
DISPLAY 0.680851 (-2510 3360);
PAINT MONO (-2510 3360);
FORCEPROP 0 LASTPIN (-2500 3850) $PN 60
J 2
(-2510 3860);
DISPLAY 0.680851 (-2510 3860);
PAINT MONO (-2510 3860);
FORCEPROP 0 LASTPIN (-2500 3400) $PN 91
J 2
(-2510 3410);
DISPLAY 0.680851 (-2510 3410);
PAINT MONO (-2510 3410);
FORCEPROP 0 LASTPIN (-2500 3900) $PN 203
J 2
(-2510 3910);
DISPLAY 0.680851 (-2510 3910);
PAINT MONO (-2510 3910);
FORCEPROP 0 LASTPIN (-2500 3450) $PN 234
J 2
(-2510 3460);
DISPLAY 0.680851 (-2510 3460);
PAINT MONO (-2510 3460);
FORCEPROP 0 LASTPIN (-2500 3950) $PN 205
J 2
(-2510 3960);
DISPLAY 0.680851 (-2510 3960);
PAINT MONO (-2510 3960);
FORCEPROP 0 LASTPIN (-2500 3500) $PN 236
J 2
(-2510 3510);
DISPLAY 0.680851 (-2510 3510);
PAINT MONO (-2510 3510);
FORCEPROP 0 LASTPIN (-2500 4050) $PN 218
J 2
(-2510 4060);
DISPLAY 0.680851 (-2510 4060);
PAINT MONO (-2510 4060);
FORCEPROP 0 LASTPIN (-2500 4100) $PN 217
J 2
(-2510 4110);
DISPLAY 0.680851 (-2510 4110);
PAINT MONO (-2510 4110);
FORCEPROP 0 LASTPIN (-2500 4350) $PN 64
J 2
(-2510 4360);
DISPLAY 0.680851 (-2510 4360);
PAINT MONO (-2510 4360);
FORCEPROP 0 LASTPIN (-2500 4200) $PN 84
J 2
(-2510 4210);
DISPLAY 0.680851 (-2510 4210);
PAINT MONO (-2510 4210);
FORCEPROP 0 LASTPIN (-2500 4400) $PN 209
J 2
(-2510 4410);
DISPLAY 0.680851 (-2510 4410);
PAINT MONO (-2510 4410);
FORCEPROP 0 LASTPIN (-2500 4250) $PN 229
J 2
(-2510 4260);
DISPLAY 0.680851 (-2510 4260);
PAINT MONO (-2510 4260);
FORCEPROP 0 LASTPIN (-1300 3800) $PN 7
J 0
(-1290 3810);
DISPLAY 0.680851 (-1290 3810);
PAINT MONO (-1290 3810);
FORCEPROP 0 LASTPIN (-1300 2150) $PN 100
J 0
(-1290 2160);
DISPLAY 0.680851 (-1290 2160);
PAINT MONO (-1290 2160);
FORCEPROP 0 LASTPIN (-1300 3850) $PN 9
J 0
(-1290 3860);
DISPLAY 0.680851 (-1290 3860);
PAINT MONO (-1290 3860);
FORCEPROP 0 LASTPIN (-1300 2200) $PN 102
J 0
(-1290 2210);
DISPLAY 0.680851 (-1290 2210);
PAINT MONO (-1290 2210);
FORCEPROP 0 LASTPIN (-1300 3900) $PN 152
J 0
(-1290 3910);
DISPLAY 0.680851 (-1290 3910);
PAINT MONO (-1290 3910);
FORCEPROP 0 LASTPIN (-1300 2250) $PN 245
J 0
(-1290 2260);
DISPLAY 0.680851 (-1290 2260);
PAINT MONO (-1290 2260);
FORCEPROP 0 LASTPIN (-1300 3950) $PN 154
J 0
(-1290 3960);
DISPLAY 0.680851 (-1290 3960);
PAINT MONO (-1290 3960);
FORCEPROP 0 LASTPIN (-1300 2300) $PN 247
J 0
(-1290 2310);
DISPLAY 0.680851 (-1290 2310);
PAINT MONO (-1290 2310);
FORCEPROP 0 LASTPIN (-1300 4000) $PN 14
J 0
(-1290 4010);
DISPLAY 0.680851 (-1290 4010);
PAINT MONO (-1290 4010);
FORCEPROP 0 LASTPIN (-1300 2350) $PN 107
J 0
(-1290 2360);
DISPLAY 0.680851 (-1290 2360);
PAINT MONO (-1290 2360);
FORCEPROP 0 LASTPIN (-1300 4050) $PN 16
J 0
(-1290 4060);
DISPLAY 0.680851 (-1290 4060);
PAINT MONO (-1290 4060);
FORCEPROP 0 LASTPIN (-1300 2400) $PN 109
J 0
(-1290 2410);
DISPLAY 0.680851 (-1290 2410);
PAINT MONO (-1290 2410);
FORCEPROP 0 LASTPIN (-1300 4100) $PN 159
J 0
(-1290 4110);
DISPLAY 0.680851 (-1290 4110);
PAINT MONO (-1290 4110);
FORCEPROP 0 LASTPIN (-1300 2450) $PN 252
J 0
(-1290 2460);
DISPLAY 0.680851 (-1290 2460);
PAINT MONO (-1290 2460);
FORCEPROP 0 LASTPIN (-1300 4150) $PN 161
J 0
(-1290 4160);
DISPLAY 0.680851 (-1290 4160);
PAINT MONO (-1290 4160);
FORCEPROP 0 LASTPIN (-1300 2500) $PN 254
J 0
(-1290 2510);
DISPLAY 0.680851 (-1290 2510);
PAINT MONO (-1290 2510);
FORCEPROP 0 LASTPIN (-1300 4200) $PN 18
J 0
(-1290 4210);
DISPLAY 0.680851 (-1290 4210);
PAINT MONO (-1290 4210);
FORCEPROP 0 LASTPIN (-1300 2550) $PN 111
J 0
(-1290 2560);
DISPLAY 0.680851 (-1290 2560);
PAINT MONO (-1290 2560);
FORCEPROP 0 LASTPIN (-1300 4250) $PN 20
J 0
(-1290 4260);
DISPLAY 0.680851 (-1290 4260);
PAINT MONO (-1290 4260);
FORCEPROP 0 LASTPIN (-1300 2600) $PN 113
J 0
(-1290 2610);
DISPLAY 0.680851 (-1290 2610);
PAINT MONO (-1290 2610);
FORCEPROP 0 LASTPIN (-1300 4300) $PN 163
J 0
(-1290 4310);
DISPLAY 0.680851 (-1290 4310);
PAINT MONO (-1290 4310);
FORCEPROP 0 LASTPIN (-1300 2650) $PN 256
J 0
(-1290 2660);
DISPLAY 0.680851 (-1290 2660);
PAINT MONO (-1290 2660);
FORCEPROP 0 LASTPIN (-1300 4350) $PN 165
J 0
(-1290 4360);
DISPLAY 0.680851 (-1290 4360);
PAINT MONO (-1290 4360);
FORCEPROP 0 LASTPIN (-1300 2700) $PN 258
J 0
(-1290 2710);
DISPLAY 0.680851 (-1290 2710);
PAINT MONO (-1290 2710);
FORCEPROP 0 LASTPIN (-1300 4400) $PN 25
J 0
(-1290 4410);
DISPLAY 0.680851 (-1290 4410);
PAINT MONO (-1290 4410);
FORCEPROP 0 LASTPIN (-1300 2750) $PN 118
J 0
(-1290 2760);
DISPLAY 0.680851 (-1290 2760);
PAINT MONO (-1290 2760);
FORCEPROP 0 LASTPIN (-1300 4450) $PN 27
J 0
(-1290 4460);
DISPLAY 0.680851 (-1290 4460);
PAINT MONO (-1290 4460);
FORCEPROP 0 LASTPIN (-1300 2800) $PN 120
J 0
(-1290 2810);
DISPLAY 0.680851 (-1290 2810);
PAINT MONO (-1290 2810);
FORCEPROP 0 LASTPIN (-1300 4500) $PN 170
J 0
(-1290 4510);
DISPLAY 0.680851 (-1290 4510);
PAINT MONO (-1290 4510);
FORCEPROP 0 LASTPIN (-1300 2850) $PN 263
J 0
(-1290 2860);
DISPLAY 0.680851 (-1290 2860);
PAINT MONO (-1290 2860);
FORCEPROP 0 LASTPIN (-1300 4550) $PN 172
J 0
(-1290 4560);
DISPLAY 0.680851 (-1290 4560);
PAINT MONO (-1290 4560);
FORCEPROP 0 LASTPIN (-1300 2900) $PN 265
J 0
(-1290 2910);
DISPLAY 0.680851 (-1290 2910);
PAINT MONO (-1290 2910);
FORCEPROP 0 LASTPIN (-1300 4600) $PN 29
J 0
(-1290 4610);
DISPLAY 0.680851 (-1290 4610);
PAINT MONO (-1290 4610);
FORCEPROP 0 LASTPIN (-1300 2950) $PN 122
J 0
(-1290 2960);
DISPLAY 0.680851 (-1290 2960);
PAINT MONO (-1290 2960);
FORCEPROP 0 LASTPIN (-1300 4650) $PN 31
J 0
(-1290 4660);
DISPLAY 0.680851 (-1290 4660);
PAINT MONO (-1290 4660);
FORCEPROP 0 LASTPIN (-1300 3000) $PN 124
J 0
(-1290 3010);
DISPLAY 0.680851 (-1290 3010);
PAINT MONO (-1290 3010);
FORCEPROP 0 LASTPIN (-1300 4700) $PN 174
J 0
(-1290 4710);
DISPLAY 0.680851 (-1290 4710);
PAINT MONO (-1290 4710);
FORCEPROP 0 LASTPIN (-1300 3050) $PN 267
J 0
(-1290 3060);
DISPLAY 0.680851 (-1290 3060);
PAINT MONO (-1290 3060);
FORCEPROP 0 LASTPIN (-1300 4750) $PN 176
J 0
(-1290 4760);
DISPLAY 0.680851 (-1290 4760);
PAINT MONO (-1290 4760);
FORCEPROP 0 LASTPIN (-1300 3100) $PN 269
J 0
(-1290 3110);
DISPLAY 0.680851 (-1290 3110);
PAINT MONO (-1290 3110);
FORCEPROP 0 LASTPIN (-1300 4800) $PN 36
J 0
(-1290 4810);
DISPLAY 0.680851 (-1290 4810);
PAINT MONO (-1290 4810);
FORCEPROP 0 LASTPIN (-1300 3150) $PN 129
J 0
(-1290 3160);
DISPLAY 0.680851 (-1290 3160);
PAINT MONO (-1290 3160);
FORCEPROP 0 LASTPIN (-1300 4850) $PN 38
J 0
(-1290 4860);
DISPLAY 0.680851 (-1290 4860);
PAINT MONO (-1290 4860);
FORCEPROP 0 LASTPIN (-1300 3200) $PN 131
J 0
(-1290 3210);
DISPLAY 0.680851 (-1290 3210);
PAINT MONO (-1290 3210);
FORCEPROP 0 LASTPIN (-1300 4900) $PN 181
J 0
(-1290 4910);
DISPLAY 0.680851 (-1290 4910);
PAINT MONO (-1290 4910);
FORCEPROP 0 LASTPIN (-1300 3250) $PN 274
J 0
(-1290 3260);
DISPLAY 0.680851 (-1290 3260);
PAINT MONO (-1290 3260);
FORCEPROP 0 LASTPIN (-1300 4950) $PN 183
J 0
(-1290 4960);
DISPLAY 0.680851 (-1290 4960);
PAINT MONO (-1290 4960);
FORCEPROP 0 LASTPIN (-1300 3300) $PN 276
J 0
(-1290 3310);
DISPLAY 0.680851 (-1290 3310);
PAINT MONO (-1290 3310);
FORCEPROP 0 LASTPIN (-1300 5000) $PN 40
J 0
(-1290 5010);
DISPLAY 0.680851 (-1290 5010);
PAINT MONO (-1290 5010);
FORCEPROP 0 LASTPIN (-1300 3350) $PN 133
J 0
(-1290 3360);
DISPLAY 0.680851 (-1290 3360);
PAINT MONO (-1290 3360);
FORCEPROP 0 LASTPIN (-1300 5050) $PN 42
J 0
(-1290 5060);
DISPLAY 0.680851 (-1290 5060);
PAINT MONO (-1290 5060);
FORCEPROP 0 LASTPIN (-1300 3400) $PN 135
J 0
(-1290 3410);
DISPLAY 0.680851 (-1290 3410);
PAINT MONO (-1290 3410);
FORCEPROP 0 LASTPIN (-1300 5100) $PN 185
J 0
(-1290 5110);
DISPLAY 0.680851 (-1290 5110);
PAINT MONO (-1290 5110);
FORCEPROP 0 LASTPIN (-1300 3450) $PN 278
J 0
(-1290 3460);
DISPLAY 0.680851 (-1290 3460);
PAINT MONO (-1290 3460);
FORCEPROP 0 LASTPIN (-1300 5150) $PN 187
J 0
(-1290 5160);
DISPLAY 0.680851 (-1290 5160);
PAINT MONO (-1290 5160);
FORCEPROP 0 LASTPIN (-1300 3500) $PN 280
J 0
(-1290 3510);
DISPLAY 0.680851 (-1290 3510);
PAINT MONO (-1290 3510);
FORCEPROP 0 LASTPIN (-1300 5200) $PN 47
J 0
(-1290 5210);
DISPLAY 0.680851 (-1290 5210);
PAINT MONO (-1290 5210);
FORCEPROP 0 LASTPIN (-1300 3550) $PN 140
J 0
(-1290 3560);
DISPLAY 0.680851 (-1290 3560);
PAINT MONO (-1290 3560);
FORCEPROP 0 LASTPIN (-1300 5250) $PN 49
J 0
(-1290 5260);
DISPLAY 0.680851 (-1290 5260);
PAINT MONO (-1290 5260);
FORCEPROP 0 LASTPIN (-1300 3600) $PN 142
J 0
(-1290 3610);
DISPLAY 0.680851 (-1290 3610);
PAINT MONO (-1290 3610);
FORCEPROP 0 LASTPIN (-1300 5300) $PN 192
J 0
(-1290 5310);
DISPLAY 0.680851 (-1290 5310);
PAINT MONO (-1290 5310);
FORCEPROP 0 LASTPIN (-1300 3650) $PN 285
J 0
(-1290 3660);
DISPLAY 0.680851 (-1290 3660);
PAINT MONO (-1290 3660);
FORCEPROP 0 LASTPIN (-1300 5350) $PN 194
J 0
(-1290 5360);
DISPLAY 0.680851 (-1290 5360);
PAINT MONO (-1290 5360);
FORCEPROP 0 LASTPIN (-1300 3700) $PN 287
J 0
(-1290 3710);
DISPLAY 0.680851 (-1290 3710);
PAINT MONO (-1290 3710);
FORCEPROP 0 LASTPIN (-2500 2850) $PN 148
J 2
(-2510 2860);
DISPLAY 0.680851 (-2510 2860);
PAINT MONO (-2510 2860);
FORCEPROP 0 LASTPIN (-2500 2750) $PN 4
J 2
(-2510 2760);
DISPLAY 0.680851 (-2510 2760);
PAINT MONO (-2510 2760);
FORCEPROP 0 LASTPIN (-2500 2800) $PN 5
J 2
(-2510 2810);
DISPLAY 0.680851 (-2510 2810);
PAINT MONO (-2510 2810);
FORCEPROP 0 LASTPIN (-2500 1950) $PN 86
J 2
(-2510 1960);
DISPLAY 0.680851 (-2510 1960);
PAINT MONO (-2510 1960);
FORCEPROP 0 LASTPIN (-2500 1900) $PN 87
J 2
(-2510 1910);
DISPLAY 0.680851 (-2510 1910);
PAINT MONO (-2510 1910);
FORCEPROP 0 LASTPIN (-2500 4550) $PN 74
J 2
(-2510 4560);
DISPLAY 0.680851 (-2510 4560);
PAINT MONO (-2510 4560);
FORCEPROP 0 LASTPIN (-2500 4500) $PN 227
J 2
(-2510 4510);
DISPLAY 0.680851 (-2510 4510);
PAINT MONO (-2510 4510);
FORCEPROP 0 LASTPIN (-2500 2500) $PN 147
J 2
(-2510 2510);
DISPLAY 0.680851 (-2510 2510);
PAINT MONO (-2510 2510);
FORCEPROP 0 LASTPIN (-2500 3050) $PN 207
J 2
(-2510 3060);
DISPLAY 0.680851 (-2510 3060);
PAINT MONO (-2510 3060);
FORCEPROP 0 LASTPIN (-2500 2100) $PN 2
J 2
(-2510 2110);
DISPLAY 0.680851 (-2510 2110);
PAINT MONO (-2510 2110);
FORCEPROP 0 LASTPIN (-2500 2150) $PN 144
J 2
(-2510 2160);
DISPLAY 0.680851 (-2510 2160);
PAINT MONO (-2510 2160);
FORCEPROP 0 LASTPIN (-2500 2200) $PN 149
J 2
(-2510 2210);
DISPLAY 0.680851 (-2510 2210);
PAINT MONO (-2510 2210);
FORCEPROP 0 LASTPIN (-2500 2250) $PN 150
J 2
(-2510 2260);
DISPLAY 0.680851 (-2510 2260);
PAINT MONO (-2510 2260);
FORCEPROP 0 LASTPIN (-2500 2300) $PN 220
J 2
(-2510 2310);
DISPLAY 0.680851 (-2510 2310);
PAINT MONO (-2510 2310);
FORCEPROP 0 LASTPIN (-2500 2350) $PN 231
J 2
(-2510 2360);
DISPLAY 0.680851 (-2510 2360);
PAINT MONO (-2510 2360);
FORCEPROP 0 LASTPIN (-2500 2400) $PN 232
J 2
(-2510 2410);
DISPLAY 0.680851 (-2510 2410);
PAINT MONO (-2510 2410);
FORCEPROP 0 LASTPIN (-2500 2900) $PN 3
J 2
(-2510 2910);
DISPLAY 0.680851 (-2510 2910);
PAINT MONO (-2510 2910);
FORCEPROP 1 LAST NEEDS_NO_SIZE TRUE
J 0
(-1900 3625);
DISPLAY 0.723404 (-1900 3625);
PAINT GREEN (-1900 3625);
DISPLAY INVISIBLE (-1900 3625);
FORCEPROP 1 LAST CDS_LMAN_SYM_OUTLINE -450,1875,450,-1875
J 0
(-1900 3625);
DISPLAY 0.468085 (-1900 3625);
PAINT GREEN (-1900 3625);
DISPLAY INVISIBLE (-1900 3625);
FORCEPROP 2 LAST CDS_LIB pure_quanta
J 0
(-1900 3625);
DISPLAY INVISIBLE (-1900 3625);
FORCEPROP 1 LAST PATH I179
J 0
(-1900 3625);
DISPLAY 0.723404 (-1900 3625);
PAINT GREEN (-1900 3625);
DISPLAY INVISIBLE (-1900 3625);
FORCEPROP 2 LAST CDS_LOCATION J27
J 0
(-2350 5850);
DISPLAY 1.021277 (-2350 5850);
DISPLAY INVISIBLE (-2350 5850);
FORCEPROP 0 LAST $SEC 1
J 0
(-2325 5850);
DISPLAY 0.680851 (-2325 5850);
PAINT MONO (-2325 5850);
DISPLAY INVISIBLE (-2325 5850);
FORCEPROP 2 LAST CDS_SEC 1
J 0
(-2350 5850);
DISPLAY 1.021277 (-2350 5850);
DISPLAY INVISIBLE (-2350 5850);
FORCEADD OFFPAGE..1
(-3650 4100);
FORCEPROP 2 LAST $XR0 56 
J 0
(-3871 4100);
DISPLAY 0.638298 (-3871 4100);
PAINT MONO (-3871 4100);
FORCEPROP 2 LAST CDS_LIB standard
J 0
(-3650 4100);
PAINT MONO (-3650 4100);
DISPLAY INVISIBLE (-3650 4100);
FORCEPROP 1 LAST OFFPAGE TRUE
J 0
(-3325 3975);
DISPLAY 0.872340 (-3325 3975);
DISPLAY INVISIBLE (-3325 3975);
FORCEPROP 1 LAST COMMENT_BODY TRUE
J 0
(-3525 4000);
DISPLAY 0.872340 (-3525 4000);
PAINT GREEN (-3525 4000);
DISPLAY INVISIBLE (-3525 4000);
FORCEPROP 2 LAST PATH I18
J 0
(-3600 4175);
DISPLAY 1.021277 (-3600 4175);
DISPLAY INVISIBLE (-3600 4175);
FORCEADD SCONN288_ADR50017P130CC..2
(775 4350);
FORCEPROP 1 LAST PART_NUMBER DFHST8FS461
J 0
(182 5650);
DISPLAY 0.723404 (182 5650);
PAINT GREEN (182 5650);
DISPLAY INVISIBLE (182 5650);
FORCEPROP 1 LAST MATERIAL IO
J 0
(182 5523);
DISPLAY 0.723404 (182 5523);
PAINT GREEN (182 5523);
FORCEPROP 2 LAST PART_TYPE SMLF
J 0
(193 5803);
DISPLAY 1.021277 (193 5803);
FORCEPROP 2 LAST VALUE SCONN288_ADR50017-P130CC
J 0
(193 5753);
DISPLAY 1.021277 (193 5753);
FORCEPROP 1 LAST LOCATION J27
J 0
(175 5700);
DISPLAY 0.723404 (175 5700);
PAINT GREEN (175 5700);
FORCEPROP 0 LASTPIN (1525 4400) $PN 12
J 0
(1535 4410);
DISPLAY 0.680851 (1535 4410);
PAINT MONO (1535 4410);
FORCEPROP 0 LASTPIN (1525 4450) $PN 11
J 0
(1535 4460);
DISPLAY 0.680851 (1535 4460);
PAINT MONO (1535 4460);
FORCEPROP 0 LASTPIN (1525 3350) $PN 105
J 0
(1535 3360);
DISPLAY 0.680851 (1535 3360);
PAINT MONO (1535 3360);
FORCEPROP 0 LASTPIN (1525 3400) $PN 104
J 0
(1535 3410);
DISPLAY 0.680851 (1535 3410);
PAINT MONO (1535 3410);
FORCEPROP 0 LASTPIN (1525 4500) $PN 23
J 0
(1535 4510);
DISPLAY 0.680851 (1535 4510);
PAINT MONO (1535 4510);
FORCEPROP 0 LASTPIN (1525 4550) $PN 22
J 0
(1535 4560);
DISPLAY 0.680851 (1535 4560);
PAINT MONO (1535 4560);
FORCEPROP 0 LASTPIN (1525 3450) $PN 116
J 0
(1535 3460);
DISPLAY 0.680851 (1535 3460);
PAINT MONO (1535 3460);
FORCEPROP 0 LASTPIN (1525 3500) $PN 115
J 0
(1535 3510);
DISPLAY 0.680851 (1535 3510);
PAINT MONO (1535 3510);
FORCEPROP 0 LASTPIN (1525 4600) $PN 34
J 0
(1535 4610);
DISPLAY 0.680851 (1535 4610);
PAINT MONO (1535 4610);
FORCEPROP 0 LASTPIN (1525 4650) $PN 33
J 0
(1535 4660);
DISPLAY 0.680851 (1535 4660);
PAINT MONO (1535 4660);
FORCEPROP 0 LASTPIN (1525 3550) $PN 127
J 0
(1535 3560);
DISPLAY 0.680851 (1535 3560);
PAINT MONO (1535 3560);
FORCEPROP 0 LASTPIN (1525 3600) $PN 126
J 0
(1535 3610);
DISPLAY 0.680851 (1535 3610);
PAINT MONO (1535 3610);
FORCEPROP 0 LASTPIN (1525 4700) $PN 45
J 0
(1535 4710);
DISPLAY 0.680851 (1535 4710);
PAINT MONO (1535 4710);
FORCEPROP 0 LASTPIN (1525 4750) $PN 44
J 0
(1535 4760);
DISPLAY 0.680851 (1535 4760);
PAINT MONO (1535 4760);
FORCEPROP 0 LASTPIN (1525 3650) $PN 138
J 0
(1535 3660);
DISPLAY 0.680851 (1535 3660);
PAINT MONO (1535 3660);
FORCEPROP 0 LASTPIN (1525 3700) $PN 137
J 0
(1535 3710);
DISPLAY 0.680851 (1535 3710);
PAINT MONO (1535 3710);
FORCEPROP 0 LASTPIN (1525 4800) $PN 56
J 0
(1535 4810);
DISPLAY 0.680851 (1535 4810);
PAINT MONO (1535 4810);
FORCEPROP 0 LASTPIN (1525 4850) $PN 55
J 0
(1535 4860);
DISPLAY 0.680851 (1535 4860);
PAINT MONO (1535 4860);
FORCEPROP 0 LASTPIN (1525 3750) $PN 238
J 0
(1535 3760);
DISPLAY 0.680851 (1535 3760);
PAINT MONO (1535 3760);
FORCEPROP 0 LASTPIN (1525 3800) $PN 239
J 0
(1535 3810);
DISPLAY 0.680851 (1535 3810);
PAINT MONO (1535 3810);
FORCEPROP 0 LASTPIN (1525 4900) $PN 156
J 0
(1535 4910);
DISPLAY 0.680851 (1535 4910);
PAINT MONO (1535 4910);
FORCEPROP 0 LASTPIN (1525 4950) $PN 157
J 0
(1535 4960);
DISPLAY 0.680851 (1535 4960);
PAINT MONO (1535 4960);
FORCEPROP 0 LASTPIN (1525 3850) $PN 249
J 0
(1535 3860);
DISPLAY 0.680851 (1535 3860);
PAINT MONO (1535 3860);
FORCEPROP 0 LASTPIN (1525 3900) $PN 250
J 0
(1535 3910);
DISPLAY 0.680851 (1535 3910);
PAINT MONO (1535 3910);
FORCEPROP 0 LASTPIN (1525 5000) $PN 167
J 0
(1535 5010);
DISPLAY 0.680851 (1535 5010);
PAINT MONO (1535 5010);
FORCEPROP 0 LASTPIN (1525 5050) $PN 168
J 0
(1535 5060);
DISPLAY 0.680851 (1535 5060);
PAINT MONO (1535 5060);
FORCEPROP 0 LASTPIN (1525 3950) $PN 260
J 0
(1535 3960);
DISPLAY 0.680851 (1535 3960);
PAINT MONO (1535 3960);
FORCEPROP 0 LASTPIN (1525 4000) $PN 261
J 0
(1535 4010);
DISPLAY 0.680851 (1535 4010);
PAINT MONO (1535 4010);
FORCEPROP 0 LASTPIN (1525 5100) $PN 178
J 0
(1535 5110);
DISPLAY 0.680851 (1535 5110);
PAINT MONO (1535 5110);
FORCEPROP 0 LASTPIN (1525 5150) $PN 179
J 0
(1535 5160);
DISPLAY 0.680851 (1535 5160);
PAINT MONO (1535 5160);
FORCEPROP 0 LASTPIN (1525 4050) $PN 271
J 0
(1535 4060);
DISPLAY 0.680851 (1535 4060);
PAINT MONO (1535 4060);
FORCEPROP 0 LASTPIN (1525 4100) $PN 272
J 0
(1535 4110);
DISPLAY 0.680851 (1535 4110);
PAINT MONO (1535 4110);
FORCEPROP 0 LASTPIN (1525 5200) $PN 189
J 0
(1535 5210);
DISPLAY 0.680851 (1535 5210);
PAINT MONO (1535 5210);
FORCEPROP 0 LASTPIN (1525 5250) $PN 190
J 0
(1535 5260);
DISPLAY 0.680851 (1535 5260);
PAINT MONO (1535 5260);
FORCEPROP 0 LASTPIN (1525 4150) $PN 282
J 0
(1535 4160);
DISPLAY 0.680851 (1535 4160);
PAINT MONO (1535 4160);
FORCEPROP 0 LASTPIN (1525 4200) $PN 283
J 0
(1535 4210);
DISPLAY 0.680851 (1535 4210);
PAINT MONO (1535 4210);
FORCEPROP 0 LASTPIN (1525 5300) $PN 200
J 0
(1535 5310);
DISPLAY 0.680851 (1535 5310);
PAINT MONO (1535 5310);
FORCEPROP 0 LASTPIN (1525 5350) $PN 201
J 0
(1535 5360);
DISPLAY 0.680851 (1535 5360);
PAINT MONO (1535 5360);
FORCEPROP 0 LASTPIN (1525 4250) $PN 94
J 0
(1535 4260);
DISPLAY 0.680851 (1535 4260);
PAINT MONO (1535 4260);
FORCEPROP 0 LASTPIN (1525 4300) $PN 93
J 0
(1535 4310);
DISPLAY 0.680851 (1535 4310);
PAINT MONO (1535 4310);
FORCEPROP 1 LAST NEEDS_NO_SIZE TRUE
J 0
(775 4350);
DISPLAY 0.723404 (775 4350);
PAINT GREEN (775 4350);
DISPLAY INVISIBLE (775 4350);
FORCEPROP 1 LAST CDS_LMAN_SYM_OUTLINE -600,1150,600,-1150
J 0
(775 4350);
DISPLAY 0.468085 (775 4350);
PAINT GREEN (775 4350);
DISPLAY INVISIBLE (775 4350);
FORCEPROP 2 LAST CDS_LIB pure_quanta
J 0
(775 4350);
DISPLAY INVISIBLE (775 4350);
FORCEPROP 1 LAST PATH I180
J 0
(775 4350);
DISPLAY 0.723404 (775 4350);
PAINT GREEN (775 4350);
DISPLAY INVISIBLE (775 4350);
FORCEPROP 0 LAST $SEC 2
J 0
(200 5875);
DISPLAY 0.680851 (200 5875);
PAINT MONO (200 5875);
DISPLAY INVISIBLE (200 5875);
FORCEPROP 0 LAST CDS_SEC 2
J 0
(200 5875);
DISPLAY 1.021277 (200 5875);
DISPLAY INVISIBLE (200 5875);
FORCEADD OFFPAGE..1
(-2475 2600);
FORCEPROP 2 LAST $XR7 113 
J 0
(-3567 2600);
DISPLAY 0.638298 (-3567 2600);
PAINT MONO (-3567 2600);
FORCEPROP 2 LAST $XR6 112 
J 0
(-3447 2600);
DISPLAY 0.638298 (-3447 2600);
PAINT MONO (-3447 2600);
FORCEPROP 2 LAST $XR5 111 
J 0
(-3327 2600);
DISPLAY 0.638298 (-3327 2600);
PAINT MONO (-3327 2600);
FORCEPROP 2 LAST $XR4 110 
J 0
(-3207 2600);
DISPLAY 0.638298 (-3207 2600);
PAINT MONO (-3207 2600);
FORCEPROP 2 LAST $XR3 109 
J 0
(-3087 2600);
DISPLAY 0.638298 (-3087 2600);
PAINT MONO (-3087 2600);
FORCEPROP 2 LAST $XR2 107 
J 0
(-2967 2600);
DISPLAY 0.638298 (-2967 2600);
PAINT MONO (-2967 2600);
FORCEPROP 2 LAST $XR1 106 
J 0
(-2847 2600);
DISPLAY 0.638298 (-2847 2600);
PAINT MONO (-2847 2600);
FORCEPROP 2 LAST $XR0 230 
J 0
(-2727 2600);
DISPLAY 0.638298 (-2727 2600);
PAINT MONO (-2727 2600);
FORCEPROP 2 LAST CDS_LIB standard
J 2
(-2475 2600);
DISPLAY INVISIBLE (-2475 2600);
FORCEPROP 1 LAST OFFPAGE TRUE
J 0
(-2150 2475);
DISPLAY 0.872340 (-2150 2475);
DISPLAY INVISIBLE (-2150 2475);
FORCEPROP 1 LAST COMMENT_BODY TRUE
J 0
(-2350 2500);
DISPLAY 0.872340 (-2350 2500);
PAINT GREEN (-2350 2500);
DISPLAY INVISIBLE (-2350 2500);
FORCEPROP 2 LAST PATH I181
J 2
(-2650 2675);
DISPLAY 1.021277 (-2650 2675);
DISPLAY INVISIBLE (-2650 2675);
FORCEADD Q_RES..1
(-3700 2675);
FORCEPROP 1 LAST PART_NUMBER CS04992FB07
J 0
(-3600 2650);
DISPLAY 0.404255 (-3600 2650);
DISPLAY INVISIBLE (-3600 2650);
FORCEPROP 1 LAST TOLERANCE 1%
J 0
(-3475 2675);
DISPLAY 0.510638 (-3475 2675);
FORCEPROP 1 LAST MATERIAL CHIP
J 0
(-3875 2650);
DISPLAY 0.404255 (-3875 2650);
FORCEPROP 1 LAST VALUE 49.9
J 2
(-3475 2675);
DISPLAY 0.510638 (-3475 2675);
FORCEPROP 1 LAST $LOCATION R3901
J 0
(-3950 2675);
DISPLAY 0.638298 (-3950 2675);
FORCEPROP 1 LASTPIN (-3800 2675) $PN 1
J 0
(-3788 2687);
DISPLAY 0.787234 (-3788 2687);
PAINT MONO (-3788 2687);
FORCEPROP 1 LASTPIN (-3600 2675) $PN 2
J 0
(-3638 2687);
DISPLAY 0.787234 (-3638 2687);
PAINT MONO (-3638 2687);
FORCEPROP 2 LAST CDS_LIB pure_quanta
J 0
(-3700 2675);
DISPLAY INVISIBLE (-3700 2675);
FORCEPROP 1 LAST PACK_TYPE 0402LF
J 0
(-3400 2675);
DISPLAY 0.510638 (-3400 2675);
DISPLAY INVISIBLE (-3400 2675);
FORCEPROP 1 LAST WATTAGE 1/16W
J 2
(-3400 2625);
DISPLAY 0.404255 (-3400 2625);
DISPLAY INVISIBLE (-3400 2625);
FORCEPROP 1 LAST PATH I182
J 0
(-3750 2825);
DISPLAY 0.978723 (-3750 2825);
PAINT WHITE (-3750 2825);
DISPLAY INVISIBLE (-3750 2825);
FORCEPROP 0 LAST CDS_LOCATION R3901
J 0
(-3850 2725);
DISPLAY 1.021277 (-3850 2725);
DISPLAY INVISIBLE (-3850 2725);
FORCEPROP 0 LAST $SEC 1
J 0
(-3850 2725);
DISPLAY 0.680851 (-3850 2725);
PAINT MONO (-3850 2725);
DISPLAY INVISIBLE (-3850 2725);
FORCEPROP 0 LAST CDS_SEC 1
J 0
(-3850 2725);
DISPLAY 1.021277 (-3850 2725);
DISPLAY INVISIBLE (-3850 2725);
FORCEADD OFFPAGE..1
(-3650 4500);
FORCEPROP 2 LAST $XR1 109 
J 0
(-3991 4500);
DISPLAY 0.638298 (-3991 4500);
PAINT MONO (-3991 4500);
FORCEPROP 2 LAST $XR0 56 
J 0
(-3871 4500);
DISPLAY 0.638298 (-3871 4500);
PAINT MONO (-3871 4500);
FORCEPROP 2 LAST CDS_LIB standard
J 0
(-3650 4500);
PAINT MONO (-3650 4500);
DISPLAY INVISIBLE (-3650 4500);
FORCEPROP 1 LAST OFFPAGE TRUE
J 0
(-3325 4375);
DISPLAY 0.872340 (-3325 4375);
DISPLAY INVISIBLE (-3325 4375);
FORCEPROP 1 LAST COMMENT_BODY TRUE
J 0
(-3525 4400);
DISPLAY 0.872340 (-3525 4400);
PAINT GREEN (-3525 4400);
DISPLAY INVISIBLE (-3525 4400);
FORCEPROP 2 LAST PATH I19
J 0
(-3600 4575);
DISPLAY 1.021277 (-3600 4575);
DISPLAY INVISIBLE (-3600 4575);
FORCEADD OFFPAGE..2
R 2
(-3650 1900);
FORCEPROP 2 LAST $XR0 56 
J 0
(-3874 1900);
DISPLAY 0.638298 (-3874 1900);
PAINT MONO (-3874 1900);
FORCEPROP 2 LAST CDS_LIB standard
J 0
(-3650 1900);
PAINT MONO (-3650 1900);
DISPLAY INVISIBLE (-3650 1900);
FORCEPROP 1 LAST OFFPAGE TRUE
J 2
(-3975 1775);
DISPLAY 0.872340 (-3975 1775);
DISPLAY INVISIBLE (-3975 1775);
FORCEPROP 1 LAST COMMENT_BODY TRUE
J 2
(-3605 1805);
DISPLAY 0.872340 (-3605 1805);
PAINT GREEN (-3605 1805);
DISPLAY INVISIBLE (-3605 1805);
FORCEPROP 2 LAST PATH I2
J 0
(-3600 1975);
DISPLAY 1.021277 (-3600 1975);
DISPLAY INVISIBLE (-3600 1975);
FORCEADD OFFPAGE..1
(-3650 4400);
FORCEPROP 2 LAST $XR0 56 
J 0
(-3871 4400);
DISPLAY 0.638298 (-3871 4400);
PAINT MONO (-3871 4400);
FORCEPROP 2 LAST CDS_LIB standard
J 0
(-3650 4400);
PAINT MONO (-3650 4400);
DISPLAY INVISIBLE (-3650 4400);
FORCEPROP 1 LAST OFFPAGE TRUE
J 0
(-3325 4275);
DISPLAY 0.872340 (-3325 4275);
DISPLAY INVISIBLE (-3325 4275);
FORCEPROP 1 LAST COMMENT_BODY TRUE
J 0
(-3525 4300);
DISPLAY 0.872340 (-3525 4300);
PAINT GREEN (-3525 4300);
DISPLAY INVISIBLE (-3525 4300);
FORCEPROP 2 LAST PATH I20
J 0
(-3600 4475);
DISPLAY 1.021277 (-3600 4475);
DISPLAY INVISIBLE (-3600 4475);
FORCEADD OFFPAGE..1
(-3650 4350);
FORCEPROP 2 LAST $XR0 56 
J 0
(-3871 4350);
DISPLAY 0.638298 (-3871 4350);
PAINT MONO (-3871 4350);
FORCEPROP 2 LAST CDS_LIB standard
J 0
(-3650 4350);
PAINT MONO (-3650 4350);
DISPLAY INVISIBLE (-3650 4350);
FORCEPROP 1 LAST OFFPAGE TRUE
J 0
(-3325 4225);
DISPLAY 0.872340 (-3325 4225);
DISPLAY INVISIBLE (-3325 4225);
FORCEPROP 1 LAST COMMENT_BODY TRUE
J 0
(-3525 4250);
DISPLAY 0.872340 (-3525 4250);
PAINT GREEN (-3525 4250);
DISPLAY INVISIBLE (-3525 4250);
FORCEPROP 2 LAST PATH I21
J 0
(-3600 4425);
DISPLAY 1.021277 (-3600 4425);
DISPLAY INVISIBLE (-3600 4425);
FORCEADD OFFPAGE..1
(-3650 4550);
FORCEPROP 2 LAST $XR1 109 
J 0
(-3991 4550);
DISPLAY 0.638298 (-3991 4550);
PAINT MONO (-3991 4550);
FORCEPROP 2 LAST $XR0 56 
J 0
(-3871 4550);
DISPLAY 0.638298 (-3871 4550);
PAINT MONO (-3871 4550);
FORCEPROP 2 LAST CDS_LIB standard
J 0
(-3650 4550);
PAINT MONO (-3650 4550);
DISPLAY INVISIBLE (-3650 4550);
FORCEPROP 1 LAST OFFPAGE TRUE
J 0
(-3325 4425);
DISPLAY 0.872340 (-3325 4425);
DISPLAY INVISIBLE (-3325 4425);
FORCEPROP 1 LAST COMMENT_BODY TRUE
J 0
(-3525 4450);
DISPLAY 0.872340 (-3525 4450);
PAINT GREEN (-3525 4450);
DISPLAY INVISIBLE (-3525 4450);
FORCEPROP 2 LAST PATH I22
J 0
(-3600 4625);
DISPLAY 1.021277 (-3600 4625);
DISPLAY INVISIBLE (-3600 4625);
FORCEADD OFFPAGE..1
(-3650 4975);
FORCEPROP 2 LAST $XR1 109 
J 0
(-3991 4975);
DISPLAY 0.638298 (-3991 4975);
PAINT MONO (-3991 4975);
FORCEPROP 2 LAST $XR0 56 
J 0
(-3871 4975);
DISPLAY 0.638298 (-3871 4975);
PAINT MONO (-3871 4975);
FORCEPROP 2 LAST CDS_LIB standard
J 0
(-3650 4975);
PAINT MONO (-3650 4975);
DISPLAY INVISIBLE (-3650 4975);
FORCEPROP 1 LAST OFFPAGE TRUE
J 0
(-3325 4850);
DISPLAY 0.872340 (-3325 4850);
DISPLAY INVISIBLE (-3325 4850);
FORCEPROP 1 LAST COMMENT_BODY TRUE
J 0
(-3525 4875);
DISPLAY 0.872340 (-3525 4875);
PAINT GREEN (-3525 4875);
DISPLAY INVISIBLE (-3525 4875);
FORCEPROP 2 LAST PATH I23
J 0
(-3600 5050);
DISPLAY 1.021277 (-3600 5050);
DISPLAY INVISIBLE (-3600 5050);
FORCEADD TAP..1
R 2
(-2725 3150);
FORCEPROP 3 LASTPIN (-2675 3150) SIG_NAME M_F_CPU1_SB_CB<0>
J 0
(-2665 3160);
DISPLAY 0.659574 (-2665 3160);
PAINT MONO (-2665 3160);
DISPLAY INVISIBLE (-2665 3160);
FORCEPROP 1 LASTPIN (-2675 3150) BN 0
J 2
(-2663 3158);
DISPLAY 0.680851 (-2663 3158);
PAINT GREEN (-2663 3158);
FORCEPROP 2 LAST CDS_LIB standard
J 0
(-2725 3150);
PAINT MONO (-2725 3150);
DISPLAY INVISIBLE (-2725 3150);
FORCEPROP 1 LAST BODY_TYPE PLUMBING
J 2
(-2725 3200);
DISPLAY 0.872340 (-2725 3200);
PAINT GREEN (-2725 3200);
DISPLAY INVISIBLE (-2725 3200);
FORCEPROP 1 LAST HDL_TAP TRUE
J 2
(-3050 3025);
DISPLAY 0.872340 (-3050 3025);
DISPLAY INVISIBLE (-3050 3025);
FORCEPROP 1 LAST PATH I24
J 2
(-2723 3150);
DISPLAY 0.872340 (-2723 3150);
PAINT GREEN (-2723 3150);
DISPLAY INVISIBLE (-2723 3150);
FORCEADD TAP..1
R 2
(-2725 3200);
FORCEPROP 3 LASTPIN (-2675 3200) SIG_NAME M_F_CPU1_SB_CB<1>
J 0
(-2665 3210);
DISPLAY 0.659574 (-2665 3210);
PAINT MONO (-2665 3210);
DISPLAY INVISIBLE (-2665 3210);
FORCEPROP 1 LASTPIN (-2675 3200) BN 1
J 2
(-2663 3208);
DISPLAY 0.680851 (-2663 3208);
PAINT GREEN (-2663 3208);
FORCEPROP 2 LAST CDS_LIB standard
J 0
(-2725 3200);
DISPLAY INVISIBLE (-2725 3200);
FORCEPROP 1 LAST BODY_TYPE PLUMBING
J 2
(-2725 3250);
DISPLAY 0.872340 (-2725 3250);
PAINT GREEN (-2725 3250);
DISPLAY INVISIBLE (-2725 3250);
FORCEPROP 1 LAST HDL_TAP TRUE
J 2
(-3050 3075);
DISPLAY 0.872340 (-3050 3075);
DISPLAY INVISIBLE (-3050 3075);
FORCEPROP 1 LAST PATH I25
J 2
(-2723 3200);
DISPLAY 0.872340 (-2723 3200);
PAINT GREEN (-2723 3200);
DISPLAY INVISIBLE (-2723 3200);
FORCEADD TAP..1
R 2
(-2725 3250);
FORCEPROP 3 LASTPIN (-2675 3250) SIG_NAME M_F_CPU1_SB_CB<2>
J 0
(-2665 3260);
DISPLAY 0.659574 (-2665 3260);
PAINT MONO (-2665 3260);
DISPLAY INVISIBLE (-2665 3260);
FORCEPROP 1 LASTPIN (-2675 3250) BN 2
J 2
(-2663 3258);
DISPLAY 0.680851 (-2663 3258);
PAINT GREEN (-2663 3258);
FORCEPROP 2 LAST CDS_LIB standard
J 0
(-2725 3250);
DISPLAY INVISIBLE (-2725 3250);
FORCEPROP 1 LAST BODY_TYPE PLUMBING
J 2
(-2725 3300);
DISPLAY 0.872340 (-2725 3300);
PAINT GREEN (-2725 3300);
DISPLAY INVISIBLE (-2725 3300);
FORCEPROP 1 LAST HDL_TAP TRUE
J 2
(-3050 3125);
DISPLAY 0.872340 (-3050 3125);
DISPLAY INVISIBLE (-3050 3125);
FORCEPROP 1 LAST PATH I26
J 2
(-2723 3250);
DISPLAY 0.872340 (-2723 3250);
PAINT GREEN (-2723 3250);
DISPLAY INVISIBLE (-2723 3250);
FORCEADD TAP..1
R 2
(-2725 3300);
FORCEPROP 3 LASTPIN (-2675 3300) SIG_NAME M_F_CPU1_SB_CB<3>
J 0
(-2665 3310);
DISPLAY 0.659574 (-2665 3310);
PAINT MONO (-2665 3310);
DISPLAY INVISIBLE (-2665 3310);
FORCEPROP 1 LASTPIN (-2675 3300) BN 3
J 2
(-2663 3308);
DISPLAY 0.680851 (-2663 3308);
PAINT GREEN (-2663 3308);
FORCEPROP 2 LAST CDS_LIB standard
J 0
(-2725 3300);
DISPLAY INVISIBLE (-2725 3300);
FORCEPROP 1 LAST BODY_TYPE PLUMBING
J 2
(-2725 3350);
DISPLAY 0.872340 (-2725 3350);
PAINT GREEN (-2725 3350);
DISPLAY INVISIBLE (-2725 3350);
FORCEPROP 1 LAST HDL_TAP TRUE
J 2
(-3050 3175);
DISPLAY 0.872340 (-3050 3175);
DISPLAY INVISIBLE (-3050 3175);
FORCEPROP 1 LAST PATH I27
J 2
(-2723 3300);
DISPLAY 0.872340 (-2723 3300);
PAINT GREEN (-2723 3300);
DISPLAY INVISIBLE (-2723 3300);
FORCEADD TAP..1
R 2
(-2725 3350);
FORCEPROP 3 LASTPIN (-2675 3350) SIG_NAME M_F_CPU1_SB_CB<4>
J 0
(-2665 3360);
DISPLAY 0.659574 (-2665 3360);
PAINT MONO (-2665 3360);
DISPLAY INVISIBLE (-2665 3360);
FORCEPROP 1 LASTPIN (-2675 3350) BN 4
J 2
(-2663 3358);
DISPLAY 0.680851 (-2663 3358);
PAINT GREEN (-2663 3358);
FORCEPROP 2 LAST CDS_LIB standard
J 0
(-2725 3350);
DISPLAY INVISIBLE (-2725 3350);
FORCEPROP 1 LAST BODY_TYPE PLUMBING
J 2
(-2725 3400);
DISPLAY 0.872340 (-2725 3400);
PAINT GREEN (-2725 3400);
DISPLAY INVISIBLE (-2725 3400);
FORCEPROP 1 LAST HDL_TAP TRUE
J 2
(-3050 3225);
DISPLAY 0.872340 (-3050 3225);
DISPLAY INVISIBLE (-3050 3225);
FORCEPROP 1 LAST PATH I28
J 2
(-2723 3350);
DISPLAY 0.872340 (-2723 3350);
PAINT GREEN (-2723 3350);
DISPLAY INVISIBLE (-2723 3350);
FORCEADD TAP..1
R 2
(-2725 3450);
FORCEPROP 3 LASTPIN (-2675 3450) SIG_NAME M_F_CPU1_SB_CB<6>
J 0
(-2665 3460);
DISPLAY 0.659574 (-2665 3460);
PAINT MONO (-2665 3460);
DISPLAY INVISIBLE (-2665 3460);
FORCEPROP 1 LASTPIN (-2675 3450) BN 6
J 2
(-2663 3458);
DISPLAY 0.680851 (-2663 3458);
PAINT GREEN (-2663 3458);
FORCEPROP 2 LAST CDS_LIB standard
J 0
(-2725 3450);
DISPLAY INVISIBLE (-2725 3450);
FORCEPROP 1 LAST BODY_TYPE PLUMBING
J 2
(-2725 3500);
DISPLAY 0.872340 (-2725 3500);
PAINT GREEN (-2725 3500);
DISPLAY INVISIBLE (-2725 3500);
FORCEPROP 1 LAST HDL_TAP TRUE
J 2
(-3050 3325);
DISPLAY 0.872340 (-3050 3325);
DISPLAY INVISIBLE (-3050 3325);
FORCEPROP 1 LAST PATH I29
J 2
(-2723 3450);
DISPLAY 0.872340 (-2723 3450);
PAINT GREEN (-2723 3450);
DISPLAY INVISIBLE (-2723 3450);
FORCEADD OFFPAGE..2
R 2
(-3650 1950);
FORCEPROP 2 LAST $XR0 56 
J 0
(-3874 1950);
DISPLAY 0.638298 (-3874 1950);
PAINT MONO (-3874 1950);
FORCEPROP 2 LAST CDS_LIB standard
J 0
(-3650 1950);
PAINT MONO (-3650 1950);
DISPLAY INVISIBLE (-3650 1950);
FORCEPROP 1 LAST OFFPAGE TRUE
J 2
(-3975 1825);
DISPLAY 0.872340 (-3975 1825);
DISPLAY INVISIBLE (-3975 1825);
FORCEPROP 1 LAST COMMENT_BODY TRUE
J 2
(-3605 1855);
DISPLAY 0.872340 (-3605 1855);
PAINT GREEN (-3605 1855);
DISPLAY INVISIBLE (-3605 1855);
FORCEPROP 2 LAST PATH I3
J 0
(-3600 2025);
DISPLAY 1.021277 (-3600 2025);
DISPLAY INVISIBLE (-3600 2025);
FORCEADD TAP..1
R 2
(-2725 3400);
FORCEPROP 3 LASTPIN (-2675 3400) SIG_NAME M_F_CPU1_SB_CB<5>
J 0
(-2665 3410);
DISPLAY 0.659574 (-2665 3410);
PAINT MONO (-2665 3410);
DISPLAY INVISIBLE (-2665 3410);
FORCEPROP 1 LASTPIN (-2675 3400) BN 5
J 2
(-2663 3408);
DISPLAY 0.680851 (-2663 3408);
PAINT GREEN (-2663 3408);
FORCEPROP 2 LAST CDS_LIB standard
J 0
(-2725 3400);
DISPLAY INVISIBLE (-2725 3400);
FORCEPROP 1 LAST BODY_TYPE PLUMBING
J 2
(-2725 3450);
DISPLAY 0.872340 (-2725 3450);
PAINT GREEN (-2725 3450);
DISPLAY INVISIBLE (-2725 3450);
FORCEPROP 1 LAST HDL_TAP TRUE
J 2
(-3050 3275);
DISPLAY 0.872340 (-3050 3275);
DISPLAY INVISIBLE (-3050 3275);
FORCEPROP 1 LAST PATH I30
J 2
(-2723 3400);
DISPLAY 0.872340 (-2723 3400);
PAINT GREEN (-2723 3400);
DISPLAY INVISIBLE (-2723 3400);
FORCEADD TAP..1
R 2
(-2725 3500);
FORCEPROP 3 LASTPIN (-2675 3500) SIG_NAME M_F_CPU1_SB_CB<7>
J 0
(-2665 3510);
DISPLAY 0.659574 (-2665 3510);
PAINT MONO (-2665 3510);
DISPLAY INVISIBLE (-2665 3510);
FORCEPROP 1 LASTPIN (-2675 3500) BN 7
J 2
(-2663 3508);
DISPLAY 0.680851 (-2663 3508);
PAINT GREEN (-2663 3508);
FORCEPROP 2 LAST CDS_LIB standard
J 0
(-2725 3500);
DISPLAY INVISIBLE (-2725 3500);
FORCEPROP 1 LAST BODY_TYPE PLUMBING
J 2
(-2725 3550);
DISPLAY 0.872340 (-2725 3550);
PAINT GREEN (-2725 3550);
DISPLAY INVISIBLE (-2725 3550);
FORCEPROP 1 LAST HDL_TAP TRUE
J 2
(-3050 3375);
DISPLAY 0.872340 (-3050 3375);
DISPLAY INVISIBLE (-3050 3375);
FORCEPROP 1 LAST PATH I31
J 2
(-2723 3500);
DISPLAY 0.872340 (-2723 3500);
PAINT GREEN (-2723 3500);
DISPLAY INVISIBLE (-2723 3500);
FORCEADD TAP..1
R 2
(-2725 3600);
FORCEPROP 3 LASTPIN (-2675 3600) SIG_NAME M_F_CPU1_SA_CB<0>
J 0
(-2665 3610);
DISPLAY 0.659574 (-2665 3610);
PAINT MONO (-2665 3610);
DISPLAY INVISIBLE (-2665 3610);
FORCEPROP 1 LASTPIN (-2675 3600) BN 0
J 2
(-2663 3608);
DISPLAY 0.680851 (-2663 3608);
PAINT GREEN (-2663 3608);
FORCEPROP 2 LAST CDS_LIB standard
J 0
(-2725 3600);
PAINT MONO (-2725 3600);
DISPLAY INVISIBLE (-2725 3600);
FORCEPROP 1 LAST BODY_TYPE PLUMBING
J 2
(-2725 3650);
DISPLAY 0.872340 (-2725 3650);
PAINT GREEN (-2725 3650);
DISPLAY INVISIBLE (-2725 3650);
FORCEPROP 1 LAST HDL_TAP TRUE
J 2
(-3050 3475);
DISPLAY 0.872340 (-3050 3475);
DISPLAY INVISIBLE (-3050 3475);
FORCEPROP 1 LAST PATH I32
J 2
(-2723 3600);
DISPLAY 0.872340 (-2723 3600);
PAINT GREEN (-2723 3600);
DISPLAY INVISIBLE (-2723 3600);
FORCEADD TAP..1
R 2
(-2725 3650);
FORCEPROP 3 LASTPIN (-2675 3650) SIG_NAME M_F_CPU1_SA_CB<1>
J 0
(-2665 3660);
DISPLAY 0.659574 (-2665 3660);
PAINT MONO (-2665 3660);
DISPLAY INVISIBLE (-2665 3660);
FORCEPROP 1 LASTPIN (-2675 3650) BN 1
J 2
(-2663 3658);
DISPLAY 0.680851 (-2663 3658);
PAINT GREEN (-2663 3658);
FORCEPROP 2 LAST CDS_LIB standard
J 0
(-2725 3650);
DISPLAY INVISIBLE (-2725 3650);
FORCEPROP 1 LAST BODY_TYPE PLUMBING
J 2
(-2725 3700);
DISPLAY 0.872340 (-2725 3700);
PAINT GREEN (-2725 3700);
DISPLAY INVISIBLE (-2725 3700);
FORCEPROP 1 LAST HDL_TAP TRUE
J 2
(-3050 3525);
DISPLAY 0.872340 (-3050 3525);
DISPLAY INVISIBLE (-3050 3525);
FORCEPROP 1 LAST PATH I33
J 2
(-2723 3650);
DISPLAY 0.872340 (-2723 3650);
PAINT GREEN (-2723 3650);
DISPLAY INVISIBLE (-2723 3650);
FORCEADD TAP..1
R 2
(-2725 3700);
FORCEPROP 3 LASTPIN (-2675 3700) SIG_NAME M_F_CPU1_SA_CB<2>
J 0
(-2665 3710);
DISPLAY 0.659574 (-2665 3710);
PAINT MONO (-2665 3710);
DISPLAY INVISIBLE (-2665 3710);
FORCEPROP 1 LASTPIN (-2675 3700) BN 2
J 2
(-2663 3708);
DISPLAY 0.680851 (-2663 3708);
PAINT GREEN (-2663 3708);
FORCEPROP 2 LAST CDS_LIB standard
J 0
(-2725 3700);
DISPLAY INVISIBLE (-2725 3700);
FORCEPROP 1 LAST BODY_TYPE PLUMBING
J 2
(-2725 3750);
DISPLAY 0.872340 (-2725 3750);
PAINT GREEN (-2725 3750);
DISPLAY INVISIBLE (-2725 3750);
FORCEPROP 1 LAST HDL_TAP TRUE
J 2
(-3050 3575);
DISPLAY 0.872340 (-3050 3575);
DISPLAY INVISIBLE (-3050 3575);
FORCEPROP 1 LAST PATH I34
J 2
(-2723 3700);
DISPLAY 0.872340 (-2723 3700);
PAINT GREEN (-2723 3700);
DISPLAY INVISIBLE (-2723 3700);
FORCEADD TAP..1
R 2
(-2725 3750);
FORCEPROP 3 LASTPIN (-2675 3750) SIG_NAME M_F_CPU1_SA_CB<3>
J 0
(-2665 3760);
DISPLAY 0.659574 (-2665 3760);
PAINT MONO (-2665 3760);
DISPLAY INVISIBLE (-2665 3760);
FORCEPROP 1 LASTPIN (-2675 3750) BN 3
J 2
(-2663 3758);
DISPLAY 0.680851 (-2663 3758);
PAINT GREEN (-2663 3758);
FORCEPROP 2 LAST CDS_LIB standard
J 0
(-2725 3750);
DISPLAY INVISIBLE (-2725 3750);
FORCEPROP 1 LAST BODY_TYPE PLUMBING
J 2
(-2725 3800);
DISPLAY 0.872340 (-2725 3800);
PAINT GREEN (-2725 3800);
DISPLAY INVISIBLE (-2725 3800);
FORCEPROP 1 LAST HDL_TAP TRUE
J 2
(-3050 3625);
DISPLAY 0.872340 (-3050 3625);
DISPLAY INVISIBLE (-3050 3625);
FORCEPROP 1 LAST PATH I35
J 2
(-2723 3750);
DISPLAY 0.872340 (-2723 3750);
PAINT GREEN (-2723 3750);
DISPLAY INVISIBLE (-2723 3750);
FORCEADD TAP..1
R 2
(-2725 3850);
FORCEPROP 3 LASTPIN (-2675 3850) SIG_NAME M_F_CPU1_SA_CB<5>
J 0
(-2665 3860);
DISPLAY 0.659574 (-2665 3860);
PAINT MONO (-2665 3860);
DISPLAY INVISIBLE (-2665 3860);
FORCEPROP 1 LASTPIN (-2675 3850) BN 5
J 2
(-2663 3858);
DISPLAY 0.680851 (-2663 3858);
PAINT GREEN (-2663 3858);
FORCEPROP 2 LAST CDS_LIB standard
J 0
(-2725 3850);
DISPLAY INVISIBLE (-2725 3850);
FORCEPROP 1 LAST BODY_TYPE PLUMBING
J 2
(-2725 3900);
DISPLAY 0.872340 (-2725 3900);
PAINT GREEN (-2725 3900);
DISPLAY INVISIBLE (-2725 3900);
FORCEPROP 1 LAST HDL_TAP TRUE
J 2
(-3050 3725);
DISPLAY 0.872340 (-3050 3725);
DISPLAY INVISIBLE (-3050 3725);
FORCEPROP 1 LAST PATH I36
J 2
(-2723 3850);
DISPLAY 0.872340 (-2723 3850);
PAINT GREEN (-2723 3850);
DISPLAY INVISIBLE (-2723 3850);
FORCEADD TAP..1
R 2
(-2725 3800);
FORCEPROP 3 LASTPIN (-2675 3800) SIG_NAME M_F_CPU1_SA_CB<4>
J 0
(-2665 3810);
DISPLAY 0.659574 (-2665 3810);
PAINT MONO (-2665 3810);
DISPLAY INVISIBLE (-2665 3810);
FORCEPROP 1 LASTPIN (-2675 3800) BN 4
J 2
(-2663 3808);
DISPLAY 0.680851 (-2663 3808);
PAINT GREEN (-2663 3808);
FORCEPROP 2 LAST CDS_LIB standard
J 0
(-2725 3800);
DISPLAY INVISIBLE (-2725 3800);
FORCEPROP 1 LAST BODY_TYPE PLUMBING
J 2
(-2725 3850);
DISPLAY 0.872340 (-2725 3850);
PAINT GREEN (-2725 3850);
DISPLAY INVISIBLE (-2725 3850);
FORCEPROP 1 LAST HDL_TAP TRUE
J 2
(-3050 3675);
DISPLAY 0.872340 (-3050 3675);
DISPLAY INVISIBLE (-3050 3675);
FORCEPROP 1 LAST PATH I37
J 2
(-2723 3800);
DISPLAY 0.872340 (-2723 3800);
PAINT GREEN (-2723 3800);
DISPLAY INVISIBLE (-2723 3800);
FORCEADD TAP..1
R 2
(-2725 3950);
FORCEPROP 3 LASTPIN (-2675 3950) SIG_NAME M_F_CPU1_SA_CB<7>
J 0
(-2665 3960);
DISPLAY 0.659574 (-2665 3960);
PAINT MONO (-2665 3960);
DISPLAY INVISIBLE (-2665 3960);
FORCEPROP 1 LASTPIN (-2675 3950) BN 7
J 2
(-2663 3958);
DISPLAY 0.680851 (-2663 3958);
PAINT GREEN (-2663 3958);
FORCEPROP 2 LAST CDS_LIB standard
J 0
(-2725 3950);
DISPLAY INVISIBLE (-2725 3950);
FORCEPROP 1 LAST BODY_TYPE PLUMBING
J 2
(-2725 4000);
DISPLAY 0.872340 (-2725 4000);
PAINT GREEN (-2725 4000);
DISPLAY INVISIBLE (-2725 4000);
FORCEPROP 1 LAST HDL_TAP TRUE
J 2
(-3050 3825);
DISPLAY 0.872340 (-3050 3825);
DISPLAY INVISIBLE (-3050 3825);
FORCEPROP 1 LAST PATH I38
J 2
(-2723 3950);
DISPLAY 0.872340 (-2723 3950);
PAINT GREEN (-2723 3950);
DISPLAY INVISIBLE (-2723 3950);
FORCEADD TAP..1
R 2
(-2725 3900);
FORCEPROP 3 LASTPIN (-2675 3900) SIG_NAME M_F_CPU1_SA_CB<6>
J 0
(-2665 3910);
DISPLAY 0.659574 (-2665 3910);
PAINT MONO (-2665 3910);
DISPLAY INVISIBLE (-2665 3910);
FORCEPROP 1 LASTPIN (-2675 3900) BN 6
J 2
(-2663 3908);
DISPLAY 0.680851 (-2663 3908);
PAINT GREEN (-2663 3908);
FORCEPROP 2 LAST CDS_LIB standard
J 0
(-2725 3900);
DISPLAY INVISIBLE (-2725 3900);
FORCEPROP 1 LAST BODY_TYPE PLUMBING
J 2
(-2725 3950);
DISPLAY 0.872340 (-2725 3950);
PAINT GREEN (-2725 3950);
DISPLAY INVISIBLE (-2725 3950);
FORCEPROP 1 LAST HDL_TAP TRUE
J 2
(-3050 3775);
DISPLAY 0.872340 (-3050 3775);
DISPLAY INVISIBLE (-3050 3775);
FORCEPROP 1 LAST PATH I39
J 2
(-2723 3900);
DISPLAY 0.872340 (-2723 3900);
PAINT GREEN (-2723 3900);
DISPLAY INVISIBLE (-2723 3900);
FORCEADD OFFPAGE..3
R 2
(-3650 2500);
FORCEPROP 2 LAST $XR0 114 
J 0
(-3930 2500);
DISPLAY 0.638298 (-3930 2500);
PAINT MONO (-3930 2500);
FORCEPROP 2 LAST CDS_LIB standard
J 0
(-3650 2500);
PAINT MONO (-3650 2500);
DISPLAY INVISIBLE (-3650 2500);
FORCEPROP 1 LAST OFFPAGE TRUE
J 2
(-3975 2375);
DISPLAY 0.872340 (-3975 2375);
DISPLAY INVISIBLE (-3975 2375);
FORCEPROP 1 LAST COMMENT_BODY TRUE
J 2
(-3600 2400);
DISPLAY 0.872340 (-3600 2400);
PAINT GREEN (-3600 2400);
DISPLAY INVISIBLE (-3600 2400);
FORCEPROP 2 LAST PATH I4
J 0
(-3600 2575);
DISPLAY 1.021277 (-3600 2575);
DISPLAY INVISIBLE (-3600 2575);
FORCEADD TAP..1
R 2
(-2725 4650);
FORCEPROP 3 LASTPIN (-2675 4650) SIG_NAME M_F_CPU1_SB_CA<0>
J 0
(-2665 4660);
DISPLAY 0.659574 (-2665 4660);
PAINT MONO (-2665 4660);
DISPLAY INVISIBLE (-2665 4660);
FORCEPROP 1 LASTPIN (-2675 4650) BN 0
J 2
(-2663 4658);
DISPLAY 0.680851 (-2663 4658);
PAINT GREEN (-2663 4658);
FORCEPROP 2 LAST CDS_LIB standard
J 0
(-2725 4650);
DISPLAY INVISIBLE (-2725 4650);
FORCEPROP 1 LAST BODY_TYPE PLUMBING
J 2
(-2725 4700);
DISPLAY 0.872340 (-2725 4700);
PAINT GREEN (-2725 4700);
DISPLAY INVISIBLE (-2725 4700);
FORCEPROP 1 LAST HDL_TAP TRUE
J 2
(-3050 4525);
DISPLAY 0.872340 (-3050 4525);
DISPLAY INVISIBLE (-3050 4525);
FORCEPROP 1 LAST PATH I40
J 2
(-2723 4650);
DISPLAY 0.872340 (-2723 4650);
PAINT GREEN (-2723 4650);
DISPLAY INVISIBLE (-2723 4650);
FORCEADD TAP..1
R 2
(-2725 4700);
FORCEPROP 3 LASTPIN (-2675 4700) SIG_NAME M_F_CPU1_SB_CA<1>
J 0
(-2665 4710);
DISPLAY 0.659574 (-2665 4710);
PAINT MONO (-2665 4710);
DISPLAY INVISIBLE (-2665 4710);
FORCEPROP 1 LASTPIN (-2675 4700) BN 1
J 2
(-2663 4708);
DISPLAY 0.680851 (-2663 4708);
PAINT GREEN (-2663 4708);
FORCEPROP 2 LAST CDS_LIB standard
J 0
(-2725 4700);
DISPLAY INVISIBLE (-2725 4700);
FORCEPROP 1 LAST BODY_TYPE PLUMBING
J 2
(-2725 4750);
DISPLAY 0.872340 (-2725 4750);
PAINT GREEN (-2725 4750);
DISPLAY INVISIBLE (-2725 4750);
FORCEPROP 1 LAST HDL_TAP TRUE
J 2
(-3050 4575);
DISPLAY 0.872340 (-3050 4575);
DISPLAY INVISIBLE (-3050 4575);
FORCEPROP 1 LAST PATH I41
J 2
(-2723 4700);
DISPLAY 0.872340 (-2723 4700);
PAINT GREEN (-2723 4700);
DISPLAY INVISIBLE (-2723 4700);
FORCEADD TAP..1
R 2
(-2725 4750);
FORCEPROP 3 LASTPIN (-2675 4750) SIG_NAME M_F_CPU1_SB_CA<2>
J 0
(-2665 4760);
DISPLAY 0.659574 (-2665 4760);
PAINT MONO (-2665 4760);
DISPLAY INVISIBLE (-2665 4760);
FORCEPROP 1 LASTPIN (-2675 4750) BN 2
J 2
(-2663 4758);
DISPLAY 0.680851 (-2663 4758);
PAINT GREEN (-2663 4758);
FORCEPROP 2 LAST CDS_LIB standard
J 0
(-2725 4750);
DISPLAY INVISIBLE (-2725 4750);
FORCEPROP 1 LAST BODY_TYPE PLUMBING
J 2
(-2725 4800);
DISPLAY 0.872340 (-2725 4800);
PAINT GREEN (-2725 4800);
DISPLAY INVISIBLE (-2725 4800);
FORCEPROP 1 LAST HDL_TAP TRUE
J 2
(-3050 4625);
DISPLAY 0.872340 (-3050 4625);
DISPLAY INVISIBLE (-3050 4625);
FORCEPROP 1 LAST PATH I42
J 2
(-2723 4750);
DISPLAY 0.872340 (-2723 4750);
PAINT GREEN (-2723 4750);
DISPLAY INVISIBLE (-2723 4750);
FORCEADD TAP..1
R 2
(-2725 4800);
FORCEPROP 3 LASTPIN (-2675 4800) SIG_NAME M_F_CPU1_SB_CA<3>
J 0
(-2665 4810);
DISPLAY 0.659574 (-2665 4810);
PAINT MONO (-2665 4810);
DISPLAY INVISIBLE (-2665 4810);
FORCEPROP 1 LASTPIN (-2675 4800) BN 3
J 2
(-2663 4808);
DISPLAY 0.680851 (-2663 4808);
PAINT GREEN (-2663 4808);
FORCEPROP 2 LAST CDS_LIB standard
J 0
(-2725 4800);
DISPLAY INVISIBLE (-2725 4800);
FORCEPROP 1 LAST BODY_TYPE PLUMBING
J 2
(-2725 4850);
DISPLAY 0.872340 (-2725 4850);
PAINT GREEN (-2725 4850);
DISPLAY INVISIBLE (-2725 4850);
FORCEPROP 1 LAST HDL_TAP TRUE
J 2
(-3050 4675);
DISPLAY 0.872340 (-3050 4675);
DISPLAY INVISIBLE (-3050 4675);
FORCEPROP 1 LAST PATH I43
J 2
(-2723 4800);
DISPLAY 0.872340 (-2723 4800);
PAINT GREEN (-2723 4800);
DISPLAY INVISIBLE (-2723 4800);
FORCEADD TAP..1
R 2
(-2725 4850);
FORCEPROP 3 LASTPIN (-2675 4850) SIG_NAME M_F_CPU1_SB_CA<4>
J 0
(-2665 4860);
DISPLAY 0.659574 (-2665 4860);
PAINT MONO (-2665 4860);
DISPLAY INVISIBLE (-2665 4860);
FORCEPROP 1 LASTPIN (-2675 4850) BN 4
J 2
(-2663 4858);
DISPLAY 0.680851 (-2663 4858);
PAINT GREEN (-2663 4858);
FORCEPROP 2 LAST CDS_LIB standard
J 0
(-2725 4850);
DISPLAY INVISIBLE (-2725 4850);
FORCEPROP 1 LAST BODY_TYPE PLUMBING
J 2
(-2725 4900);
DISPLAY 0.872340 (-2725 4900);
PAINT GREEN (-2725 4900);
DISPLAY INVISIBLE (-2725 4900);
FORCEPROP 1 LAST HDL_TAP TRUE
J 2
(-3050 4725);
DISPLAY 0.872340 (-3050 4725);
DISPLAY INVISIBLE (-3050 4725);
FORCEPROP 1 LAST PATH I44
J 2
(-2723 4850);
DISPLAY 0.872340 (-2723 4850);
PAINT GREEN (-2723 4850);
DISPLAY INVISIBLE (-2723 4850);
FORCEADD TAP..1
R 2
(-2725 4900);
FORCEPROP 3 LASTPIN (-2675 4900) SIG_NAME M_F_CPU1_SB_CA<5>
J 0
(-2665 4910);
DISPLAY 0.659574 (-2665 4910);
PAINT MONO (-2665 4910);
DISPLAY INVISIBLE (-2665 4910);
FORCEPROP 1 LASTPIN (-2675 4900) BN 5
J 2
(-2663 4908);
DISPLAY 0.680851 (-2663 4908);
PAINT GREEN (-2663 4908);
FORCEPROP 2 LAST CDS_LIB standard
J 0
(-2725 4900);
DISPLAY INVISIBLE (-2725 4900);
FORCEPROP 1 LAST BODY_TYPE PLUMBING
J 2
(-2725 4950);
DISPLAY 0.872340 (-2725 4950);
PAINT GREEN (-2725 4950);
DISPLAY INVISIBLE (-2725 4950);
FORCEPROP 1 LAST HDL_TAP TRUE
J 2
(-3050 4775);
DISPLAY 0.872340 (-3050 4775);
DISPLAY INVISIBLE (-3050 4775);
FORCEPROP 1 LAST PATH I45
J 2
(-2723 4900);
DISPLAY 0.872340 (-2723 4900);
PAINT GREEN (-2723 4900);
DISPLAY INVISIBLE (-2723 4900);
FORCEADD TAP..1
R 2
(-2725 4950);
FORCEPROP 3 LASTPIN (-2675 4950) SIG_NAME M_F_CPU1_SB_CA<6>
J 0
(-2665 4960);
DISPLAY 0.659574 (-2665 4960);
PAINT MONO (-2665 4960);
DISPLAY INVISIBLE (-2665 4960);
FORCEPROP 1 LASTPIN (-2675 4950) BN 6
J 2
(-2663 4958);
DISPLAY 0.680851 (-2663 4958);
PAINT GREEN (-2663 4958);
FORCEPROP 2 LAST CDS_LIB standard
J 0
(-2725 4950);
DISPLAY INVISIBLE (-2725 4950);
FORCEPROP 1 LAST BODY_TYPE PLUMBING
J 2
(-2725 5000);
DISPLAY 0.872340 (-2725 5000);
PAINT GREEN (-2725 5000);
DISPLAY INVISIBLE (-2725 5000);
FORCEPROP 1 LAST HDL_TAP TRUE
J 2
(-3050 4825);
DISPLAY 0.872340 (-3050 4825);
DISPLAY INVISIBLE (-3050 4825);
FORCEPROP 1 LAST PATH I46
J 2
(-2723 4950);
DISPLAY 0.872340 (-2723 4950);
PAINT GREEN (-2723 4950);
DISPLAY INVISIBLE (-2723 4950);
FORCEADD TAP..1
(-1075 2200);
FORCEPROP 3 LASTPIN (-1125 2200) SIG_NAME M_F_CPU1_SB_DQ<1>
J 0
(-1115 2210);
DISPLAY 0.659574 (-1115 2210);
PAINT MONO (-1115 2210);
DISPLAY INVISIBLE (-1115 2210);
FORCEPROP 1 LASTPIN (-1125 2200) BN 1
J 0
(-1137 2208);
DISPLAY 0.680851 (-1137 2208);
PAINT GREEN (-1137 2208);
FORCEPROP 2 LAST CDS_LIB standard
J 0
(-1075 2200);
PAINT MONO (-1075 2200);
DISPLAY INVISIBLE (-1075 2200);
FORCEPROP 1 LAST BODY_TYPE PLUMBING
J 0
(-1075 2250);
DISPLAY 0.872340 (-1075 2250);
PAINT GREEN (-1075 2250);
DISPLAY INVISIBLE (-1075 2250);
FORCEPROP 1 LAST HDL_TAP TRUE
J 0
(-750 2075);
DISPLAY 0.872340 (-750 2075);
DISPLAY INVISIBLE (-750 2075);
FORCEPROP 1 LAST PATH I47
J 0
(-1077 2200);
DISPLAY 0.872340 (-1077 2200);
PAINT GREEN (-1077 2200);
DISPLAY INVISIBLE (-1077 2200);
FORCEADD TAP..1
(-1075 2150);
FORCEPROP 3 LASTPIN (-1125 2150) SIG_NAME M_F_CPU1_SB_DQ<0>
J 0
(-1115 2160);
DISPLAY 0.659574 (-1115 2160);
PAINT MONO (-1115 2160);
DISPLAY INVISIBLE (-1115 2160);
FORCEPROP 1 LASTPIN (-1125 2150) BN 0
J 0
(-1137 2158);
DISPLAY 0.680851 (-1137 2158);
PAINT GREEN (-1137 2158);
FORCEPROP 2 LAST CDS_LIB standard
J 0
(-1075 2150);
PAINT MONO (-1075 2150);
DISPLAY INVISIBLE (-1075 2150);
FORCEPROP 1 LAST BODY_TYPE PLUMBING
J 0
(-1075 2200);
DISPLAY 0.872340 (-1075 2200);
PAINT GREEN (-1075 2200);
DISPLAY INVISIBLE (-1075 2200);
FORCEPROP 1 LAST HDL_TAP TRUE
J 0
(-750 2025);
DISPLAY 0.872340 (-750 2025);
DISPLAY INVISIBLE (-750 2025);
FORCEPROP 1 LAST PATH I48
J 0
(-1077 2150);
DISPLAY 0.872340 (-1077 2150);
PAINT GREEN (-1077 2150);
DISPLAY INVISIBLE (-1077 2150);
FORCEADD TAP..1
(-1075 2250);
FORCEPROP 3 LASTPIN (-1125 2250) SIG_NAME M_F_CPU1_SB_DQ<2>
J 0
(-1115 2260);
DISPLAY 0.659574 (-1115 2260);
PAINT MONO (-1115 2260);
DISPLAY INVISIBLE (-1115 2260);
FORCEPROP 1 LASTPIN (-1125 2250) BN 2
J 0
(-1137 2258);
DISPLAY 0.680851 (-1137 2258);
PAINT GREEN (-1137 2258);
FORCEPROP 2 LAST CDS_LIB standard
J 0
(-1075 2250);
PAINT MONO (-1075 2250);
DISPLAY INVISIBLE (-1075 2250);
FORCEPROP 1 LAST BODY_TYPE PLUMBING
J 0
(-1075 2300);
DISPLAY 0.872340 (-1075 2300);
PAINT GREEN (-1075 2300);
DISPLAY INVISIBLE (-1075 2300);
FORCEPROP 1 LAST HDL_TAP TRUE
J 0
(-750 2125);
DISPLAY 0.872340 (-750 2125);
DISPLAY INVISIBLE (-750 2125);
FORCEPROP 1 LAST PATH I49
J 0
(-1077 2250);
DISPLAY 0.872340 (-1077 2250);
PAINT GREEN (-1077 2250);
DISPLAY INVISIBLE (-1077 2250);
FORCEADD TAP..1
(-1075 2350);
FORCEPROP 3 LASTPIN (-1125 2350) SIG_NAME M_F_CPU1_SB_DQ<4>
J 0
(-1115 2360);
DISPLAY 0.659574 (-1115 2360);
PAINT MONO (-1115 2360);
DISPLAY INVISIBLE (-1115 2360);
FORCEPROP 1 LASTPIN (-1125 2350) BN 4
J 0
(-1137 2358);
DISPLAY 0.680851 (-1137 2358);
PAINT GREEN (-1137 2358);
FORCEPROP 2 LAST CDS_LIB standard
J 0
(-1075 2350);
PAINT MONO (-1075 2350);
DISPLAY INVISIBLE (-1075 2350);
FORCEPROP 1 LAST BODY_TYPE PLUMBING
J 0
(-1075 2400);
DISPLAY 0.872340 (-1075 2400);
PAINT GREEN (-1075 2400);
DISPLAY INVISIBLE (-1075 2400);
FORCEPROP 1 LAST HDL_TAP TRUE
J 0
(-750 2225);
DISPLAY 0.872340 (-750 2225);
DISPLAY INVISIBLE (-750 2225);
FORCEPROP 1 LAST PATH I50
J 0
(-1077 2350);
DISPLAY 0.872340 (-1077 2350);
PAINT GREEN (-1077 2350);
DISPLAY INVISIBLE (-1077 2350);
FORCEADD TAP..1
(-1075 2300);
FORCEPROP 3 LASTPIN (-1125 2300) SIG_NAME M_F_CPU1_SB_DQ<3>
J 0
(-1115 2310);
DISPLAY 0.659574 (-1115 2310);
PAINT MONO (-1115 2310);
DISPLAY INVISIBLE (-1115 2310);
FORCEPROP 1 LASTPIN (-1125 2300) BN 3
J 0
(-1137 2308);
DISPLAY 0.680851 (-1137 2308);
PAINT GREEN (-1137 2308);
FORCEPROP 2 LAST CDS_LIB standard
J 0
(-1075 2300);
PAINT MONO (-1075 2300);
DISPLAY INVISIBLE (-1075 2300);
FORCEPROP 1 LAST BODY_TYPE PLUMBING
J 0
(-1075 2350);
DISPLAY 0.872340 (-1075 2350);
PAINT GREEN (-1075 2350);
DISPLAY INVISIBLE (-1075 2350);
FORCEPROP 1 LAST HDL_TAP TRUE
J 0
(-750 2175);
DISPLAY 0.872340 (-750 2175);
DISPLAY INVISIBLE (-750 2175);
FORCEPROP 1 LAST PATH I51
J 0
(-1077 2300);
DISPLAY 0.872340 (-1077 2300);
PAINT GREEN (-1077 2300);
DISPLAY INVISIBLE (-1077 2300);
FORCEADD TAP..1
(-1075 2450);
FORCEPROP 3 LASTPIN (-1125 2450) SIG_NAME M_F_CPU1_SB_DQ<6>
J 0
(-1115 2460);
DISPLAY 0.659574 (-1115 2460);
PAINT MONO (-1115 2460);
DISPLAY INVISIBLE (-1115 2460);
FORCEPROP 1 LASTPIN (-1125 2450) BN 6
J 0
(-1137 2458);
DISPLAY 0.680851 (-1137 2458);
PAINT GREEN (-1137 2458);
FORCEPROP 2 LAST CDS_LIB standard
J 0
(-1075 2450);
PAINT MONO (-1075 2450);
DISPLAY INVISIBLE (-1075 2450);
FORCEPROP 1 LAST BODY_TYPE PLUMBING
J 0
(-1075 2500);
DISPLAY 0.872340 (-1075 2500);
PAINT GREEN (-1075 2500);
DISPLAY INVISIBLE (-1075 2500);
FORCEPROP 1 LAST HDL_TAP TRUE
J 0
(-750 2325);
DISPLAY 0.872340 (-750 2325);
DISPLAY INVISIBLE (-750 2325);
FORCEPROP 1 LAST PATH I52
J 0
(-1077 2450);
DISPLAY 0.872340 (-1077 2450);
PAINT GREEN (-1077 2450);
DISPLAY INVISIBLE (-1077 2450);
FORCEADD TAP..1
(-1075 2400);
FORCEPROP 3 LASTPIN (-1125 2400) SIG_NAME M_F_CPU1_SB_DQ<5>
J 0
(-1115 2410);
DISPLAY 0.659574 (-1115 2410);
PAINT MONO (-1115 2410);
DISPLAY INVISIBLE (-1115 2410);
FORCEPROP 1 LASTPIN (-1125 2400) BN 5
J 0
(-1137 2408);
DISPLAY 0.680851 (-1137 2408);
PAINT GREEN (-1137 2408);
FORCEPROP 2 LAST CDS_LIB standard
J 0
(-1075 2400);
PAINT MONO (-1075 2400);
DISPLAY INVISIBLE (-1075 2400);
FORCEPROP 1 LAST BODY_TYPE PLUMBING
J 0
(-1075 2450);
DISPLAY 0.872340 (-1075 2450);
PAINT GREEN (-1075 2450);
DISPLAY INVISIBLE (-1075 2450);
FORCEPROP 1 LAST HDL_TAP TRUE
J 0
(-750 2275);
DISPLAY 0.872340 (-750 2275);
DISPLAY INVISIBLE (-750 2275);
FORCEPROP 1 LAST PATH I53
J 0
(-1077 2400);
DISPLAY 0.872340 (-1077 2400);
PAINT GREEN (-1077 2400);
DISPLAY INVISIBLE (-1077 2400);
FORCEADD TAP..1
(-1075 2500);
FORCEPROP 3 LASTPIN (-1125 2500) SIG_NAME M_F_CPU1_SB_DQ<7>
J 0
(-1115 2510);
DISPLAY 0.659574 (-1115 2510);
PAINT MONO (-1115 2510);
DISPLAY INVISIBLE (-1115 2510);
FORCEPROP 1 LASTPIN (-1125 2500) BN 7
J 0
(-1137 2508);
DISPLAY 0.680851 (-1137 2508);
PAINT GREEN (-1137 2508);
FORCEPROP 2 LAST CDS_LIB standard
J 0
(-1075 2500);
PAINT MONO (-1075 2500);
DISPLAY INVISIBLE (-1075 2500);
FORCEPROP 1 LAST BODY_TYPE PLUMBING
J 0
(-1075 2550);
DISPLAY 0.872340 (-1075 2550);
PAINT GREEN (-1075 2550);
DISPLAY INVISIBLE (-1075 2550);
FORCEPROP 1 LAST HDL_TAP TRUE
J 0
(-750 2375);
DISPLAY 0.872340 (-750 2375);
DISPLAY INVISIBLE (-750 2375);
FORCEPROP 1 LAST PATH I54
J 0
(-1077 2500);
DISPLAY 0.872340 (-1077 2500);
PAINT GREEN (-1077 2500);
DISPLAY INVISIBLE (-1077 2500);
FORCEADD TAP..1
(-1075 2550);
FORCEPROP 3 LASTPIN (-1125 2550) SIG_NAME M_F_CPU1_SB_DQ<8>
J 0
(-1115 2560);
DISPLAY 0.659574 (-1115 2560);
PAINT MONO (-1115 2560);
DISPLAY INVISIBLE (-1115 2560);
FORCEPROP 1 LASTPIN (-1125 2550) BN 8
J 0
(-1137 2558);
DISPLAY 0.680851 (-1137 2558);
PAINT GREEN (-1137 2558);
FORCEPROP 2 LAST CDS_LIB standard
J 0
(-1075 2550);
PAINT MONO (-1075 2550);
DISPLAY INVISIBLE (-1075 2550);
FORCEPROP 1 LAST BODY_TYPE PLUMBING
J 0
(-1075 2600);
DISPLAY 0.872340 (-1075 2600);
PAINT GREEN (-1075 2600);
DISPLAY INVISIBLE (-1075 2600);
FORCEPROP 1 LAST HDL_TAP TRUE
J 0
(-750 2425);
DISPLAY 0.872340 (-750 2425);
DISPLAY INVISIBLE (-750 2425);
FORCEPROP 1 LAST PATH I55
J 0
(-1077 2550);
DISPLAY 0.872340 (-1077 2550);
PAINT GREEN (-1077 2550);
DISPLAY INVISIBLE (-1077 2550);
FORCEADD TAP..1
(-1075 2600);
FORCEPROP 3 LASTPIN (-1125 2600) SIG_NAME M_F_CPU1_SB_DQ<9>
J 0
(-1115 2610);
DISPLAY 0.659574 (-1115 2610);
PAINT MONO (-1115 2610);
DISPLAY INVISIBLE (-1115 2610);
FORCEPROP 1 LASTPIN (-1125 2600) BN 9
J 0
(-1137 2608);
DISPLAY 0.680851 (-1137 2608);
PAINT GREEN (-1137 2608);
FORCEPROP 2 LAST CDS_LIB standard
J 0
(-1075 2600);
PAINT MONO (-1075 2600);
DISPLAY INVISIBLE (-1075 2600);
FORCEPROP 1 LAST BODY_TYPE PLUMBING
J 0
(-1075 2650);
DISPLAY 0.872340 (-1075 2650);
PAINT GREEN (-1075 2650);
DISPLAY INVISIBLE (-1075 2650);
FORCEPROP 1 LAST HDL_TAP TRUE
J 0
(-750 2475);
DISPLAY 0.872340 (-750 2475);
DISPLAY INVISIBLE (-750 2475);
FORCEPROP 1 LAST PATH I56
J 0
(-1077 2600);
DISPLAY 0.872340 (-1077 2600);
PAINT GREEN (-1077 2600);
DISPLAY INVISIBLE (-1077 2600);
FORCEADD TAP..1
(-1075 2700);
FORCEPROP 3 LASTPIN (-1125 2700) SIG_NAME M_F_CPU1_SB_DQ<11>
J 0
(-1115 2710);
DISPLAY 0.659574 (-1115 2710);
PAINT MONO (-1115 2710);
DISPLAY INVISIBLE (-1115 2710);
FORCEPROP 1 LASTPIN (-1125 2700) BN 11
J 0
(-1137 2708);
DISPLAY 0.680851 (-1137 2708);
PAINT GREEN (-1137 2708);
FORCEPROP 2 LAST CDS_LIB standard
J 0
(-1075 2700);
PAINT MONO (-1075 2700);
DISPLAY INVISIBLE (-1075 2700);
FORCEPROP 1 LAST BODY_TYPE PLUMBING
J 0
(-1075 2750);
DISPLAY 0.872340 (-1075 2750);
PAINT GREEN (-1075 2750);
DISPLAY INVISIBLE (-1075 2750);
FORCEPROP 1 LAST HDL_TAP TRUE
J 0
(-750 2575);
DISPLAY 0.872340 (-750 2575);
DISPLAY INVISIBLE (-750 2575);
FORCEPROP 1 LAST PATH I57
J 0
(-1077 2700);
DISPLAY 0.872340 (-1077 2700);
PAINT GREEN (-1077 2700);
DISPLAY INVISIBLE (-1077 2700);
FORCEADD TAP..1
(-1075 2650);
FORCEPROP 3 LASTPIN (-1125 2650) SIG_NAME M_F_CPU1_SB_DQ<10>
J 0
(-1115 2660);
DISPLAY 0.659574 (-1115 2660);
PAINT MONO (-1115 2660);
DISPLAY INVISIBLE (-1115 2660);
FORCEPROP 1 LASTPIN (-1125 2650) BN 10
J 0
(-1137 2658);
DISPLAY 0.680851 (-1137 2658);
PAINT GREEN (-1137 2658);
FORCEPROP 2 LAST CDS_LIB standard
J 0
(-1075 2650);
PAINT MONO (-1075 2650);
DISPLAY INVISIBLE (-1075 2650);
FORCEPROP 1 LAST BODY_TYPE PLUMBING
J 0
(-1075 2700);
DISPLAY 0.872340 (-1075 2700);
PAINT GREEN (-1075 2700);
DISPLAY INVISIBLE (-1075 2700);
FORCEPROP 1 LAST HDL_TAP TRUE
J 0
(-750 2525);
DISPLAY 0.872340 (-750 2525);
DISPLAY INVISIBLE (-750 2525);
FORCEPROP 1 LAST PATH I58
J 0
(-1077 2650);
DISPLAY 0.872340 (-1077 2650);
PAINT GREEN (-1077 2650);
DISPLAY INVISIBLE (-1077 2650);
FORCEADD TAP..1
(-1075 2800);
FORCEPROP 3 LASTPIN (-1125 2800) SIG_NAME M_F_CPU1_SB_DQ<13>
J 0
(-1115 2810);
DISPLAY 0.659574 (-1115 2810);
PAINT MONO (-1115 2810);
DISPLAY INVISIBLE (-1115 2810);
FORCEPROP 1 LASTPIN (-1125 2800) BN 13
J 0
(-1137 2808);
DISPLAY 0.680851 (-1137 2808);
PAINT GREEN (-1137 2808);
FORCEPROP 2 LAST CDS_LIB standard
J 0
(-1075 2800);
PAINT MONO (-1075 2800);
DISPLAY INVISIBLE (-1075 2800);
FORCEPROP 1 LAST BODY_TYPE PLUMBING
J 0
(-1075 2850);
DISPLAY 0.872340 (-1075 2850);
PAINT GREEN (-1075 2850);
DISPLAY INVISIBLE (-1075 2850);
FORCEPROP 1 LAST HDL_TAP TRUE
J 0
(-750 2675);
DISPLAY 0.872340 (-750 2675);
DISPLAY INVISIBLE (-750 2675);
FORCEPROP 1 LAST PATH I59
J 0
(-1077 2800);
DISPLAY 0.872340 (-1077 2800);
PAINT GREEN (-1077 2800);
DISPLAY INVISIBLE (-1077 2800);
FORCEADD OFFPAGE..1
(-3525 2850);
FORCEPROP 2 LAST $XR0 108 
J 0
(-3987 2850);
DISPLAY 0.638298 (-3987 2850);
PAINT MONO (-3987 2850);
FORCEPROP 2 LAST CDS_LIB standard
J 0
(-3525 2850);
PAINT MONO (-3525 2850);
DISPLAY INVISIBLE (-3525 2850);
FORCEPROP 1 LAST OFFPAGE TRUE
J 0
(-3200 2725);
DISPLAY 0.872340 (-3200 2725);
DISPLAY INVISIBLE (-3200 2725);
FORCEPROP 1 LAST COMMENT_BODY TRUE
J 0
(-3400 2750);
DISPLAY 0.872340 (-3400 2750);
PAINT GREEN (-3400 2750);
DISPLAY INVISIBLE (-3400 2750);
FORCEPROP 2 LAST PATH I6
J 0
(-3475 2925);
DISPLAY 1.021277 (-3475 2925);
DISPLAY INVISIBLE (-3475 2925);
FORCEADD TAP..1
(-1075 2850);
FORCEPROP 3 LASTPIN (-1125 2850) SIG_NAME M_F_CPU1_SB_DQ<14>
J 0
(-1115 2860);
DISPLAY 0.659574 (-1115 2860);
PAINT MONO (-1115 2860);
DISPLAY INVISIBLE (-1115 2860);
FORCEPROP 1 LASTPIN (-1125 2850) BN 14
J 0
(-1137 2858);
DISPLAY 0.680851 (-1137 2858);
PAINT GREEN (-1137 2858);
FORCEPROP 2 LAST CDS_LIB standard
J 0
(-1075 2850);
PAINT MONO (-1075 2850);
DISPLAY INVISIBLE (-1075 2850);
FORCEPROP 1 LAST BODY_TYPE PLUMBING
J 0
(-1075 2900);
DISPLAY 0.872340 (-1075 2900);
PAINT GREEN (-1075 2900);
DISPLAY INVISIBLE (-1075 2900);
FORCEPROP 1 LAST HDL_TAP TRUE
J 0
(-750 2725);
DISPLAY 0.872340 (-750 2725);
DISPLAY INVISIBLE (-750 2725);
FORCEPROP 1 LAST PATH I60
J 0
(-1077 2850);
DISPLAY 0.872340 (-1077 2850);
PAINT GREEN (-1077 2850);
DISPLAY INVISIBLE (-1077 2850);
FORCEADD TAP..1
(-1075 2950);
FORCEPROP 3 LASTPIN (-1125 2950) SIG_NAME M_F_CPU1_SB_DQ<16>
J 0
(-1115 2960);
DISPLAY 0.659574 (-1115 2960);
PAINT MONO (-1115 2960);
DISPLAY INVISIBLE (-1115 2960);
FORCEPROP 1 LASTPIN (-1125 2950) BN 16
J 0
(-1137 2958);
DISPLAY 0.680851 (-1137 2958);
PAINT GREEN (-1137 2958);
FORCEPROP 2 LAST CDS_LIB standard
J 0
(-1075 2950);
PAINT MONO (-1075 2950);
DISPLAY INVISIBLE (-1075 2950);
FORCEPROP 1 LAST BODY_TYPE PLUMBING
J 0
(-1075 3000);
DISPLAY 0.872340 (-1075 3000);
PAINT GREEN (-1075 3000);
DISPLAY INVISIBLE (-1075 3000);
FORCEPROP 1 LAST HDL_TAP TRUE
J 0
(-750 2825);
DISPLAY 0.872340 (-750 2825);
DISPLAY INVISIBLE (-750 2825);
FORCEPROP 1 LAST PATH I61
J 0
(-1077 2950);
DISPLAY 0.872340 (-1077 2950);
PAINT GREEN (-1077 2950);
DISPLAY INVISIBLE (-1077 2950);
FORCEADD TAP..1
(-1075 2900);
FORCEPROP 3 LASTPIN (-1125 2900) SIG_NAME M_F_CPU1_SB_DQ<15>
J 0
(-1115 2910);
DISPLAY 0.659574 (-1115 2910);
PAINT MONO (-1115 2910);
DISPLAY INVISIBLE (-1115 2910);
FORCEPROP 1 LASTPIN (-1125 2900) BN 15
J 0
(-1137 2908);
DISPLAY 0.680851 (-1137 2908);
PAINT GREEN (-1137 2908);
FORCEPROP 2 LAST CDS_LIB standard
J 0
(-1075 2900);
PAINT MONO (-1075 2900);
DISPLAY INVISIBLE (-1075 2900);
FORCEPROP 1 LAST BODY_TYPE PLUMBING
J 0
(-1075 2950);
DISPLAY 0.872340 (-1075 2950);
PAINT GREEN (-1075 2950);
DISPLAY INVISIBLE (-1075 2950);
FORCEPROP 1 LAST HDL_TAP TRUE
J 0
(-750 2775);
DISPLAY 0.872340 (-750 2775);
DISPLAY INVISIBLE (-750 2775);
FORCEPROP 1 LAST PATH I62
J 0
(-1077 2900);
DISPLAY 0.872340 (-1077 2900);
PAINT GREEN (-1077 2900);
DISPLAY INVISIBLE (-1077 2900);
FORCEADD TAP..1
(-1075 3000);
FORCEPROP 3 LASTPIN (-1125 3000) SIG_NAME M_F_CPU1_SB_DQ<17>
J 0
(-1115 3010);
DISPLAY 0.659574 (-1115 3010);
PAINT MONO (-1115 3010);
DISPLAY INVISIBLE (-1115 3010);
FORCEPROP 1 LASTPIN (-1125 3000) BN 17
J 0
(-1137 3008);
DISPLAY 0.680851 (-1137 3008);
PAINT GREEN (-1137 3008);
FORCEPROP 2 LAST CDS_LIB standard
J 0
(-1075 3000);
PAINT MONO (-1075 3000);
DISPLAY INVISIBLE (-1075 3000);
FORCEPROP 1 LAST BODY_TYPE PLUMBING
J 0
(-1075 3050);
DISPLAY 0.872340 (-1075 3050);
PAINT GREEN (-1075 3050);
DISPLAY INVISIBLE (-1075 3050);
FORCEPROP 1 LAST HDL_TAP TRUE
J 0
(-750 2875);
DISPLAY 0.872340 (-750 2875);
DISPLAY INVISIBLE (-750 2875);
FORCEPROP 1 LAST PATH I63
J 0
(-1077 3000);
DISPLAY 0.872340 (-1077 3000);
PAINT GREEN (-1077 3000);
DISPLAY INVISIBLE (-1077 3000);
FORCEADD TAP..1
(-1075 3050);
FORCEPROP 3 LASTPIN (-1125 3050) SIG_NAME M_F_CPU1_SB_DQ<18>
J 0
(-1115 3060);
DISPLAY 0.659574 (-1115 3060);
PAINT MONO (-1115 3060);
DISPLAY INVISIBLE (-1115 3060);
FORCEPROP 1 LASTPIN (-1125 3050) BN 18
J 0
(-1137 3058);
DISPLAY 0.680851 (-1137 3058);
PAINT GREEN (-1137 3058);
FORCEPROP 2 LAST CDS_LIB standard
J 0
(-1075 3050);
PAINT MONO (-1075 3050);
DISPLAY INVISIBLE (-1075 3050);
FORCEPROP 1 LAST BODY_TYPE PLUMBING
J 0
(-1075 3100);
DISPLAY 0.872340 (-1075 3100);
PAINT GREEN (-1075 3100);
DISPLAY INVISIBLE (-1075 3100);
FORCEPROP 1 LAST HDL_TAP TRUE
J 0
(-750 2925);
DISPLAY 0.872340 (-750 2925);
DISPLAY INVISIBLE (-750 2925);
FORCEPROP 1 LAST PATH I64
J 0
(-1077 3050);
DISPLAY 0.872340 (-1077 3050);
PAINT GREEN (-1077 3050);
DISPLAY INVISIBLE (-1077 3050);
FORCEADD TAP..1
(-1075 3100);
FORCEPROP 3 LASTPIN (-1125 3100) SIG_NAME M_F_CPU1_SB_DQ<19>
J 0
(-1115 3110);
DISPLAY 0.659574 (-1115 3110);
PAINT MONO (-1115 3110);
DISPLAY INVISIBLE (-1115 3110);
FORCEPROP 1 LASTPIN (-1125 3100) BN 19
J 0
(-1137 3108);
DISPLAY 0.680851 (-1137 3108);
PAINT GREEN (-1137 3108);
FORCEPROP 2 LAST CDS_LIB standard
J 0
(-1075 3100);
PAINT MONO (-1075 3100);
DISPLAY INVISIBLE (-1075 3100);
FORCEPROP 1 LAST BODY_TYPE PLUMBING
J 0
(-1075 3150);
DISPLAY 0.872340 (-1075 3150);
PAINT GREEN (-1075 3150);
DISPLAY INVISIBLE (-1075 3150);
FORCEPROP 1 LAST HDL_TAP TRUE
J 0
(-750 2975);
DISPLAY 0.872340 (-750 2975);
DISPLAY INVISIBLE (-750 2975);
FORCEPROP 1 LAST PATH I65
J 0
(-1077 3100);
DISPLAY 0.872340 (-1077 3100);
PAINT GREEN (-1077 3100);
DISPLAY INVISIBLE (-1077 3100);
FORCEADD TAP..1
(-1075 3150);
FORCEPROP 3 LASTPIN (-1125 3150) SIG_NAME M_F_CPU1_SB_DQ<20>
J 0
(-1115 3160);
DISPLAY 0.659574 (-1115 3160);
PAINT MONO (-1115 3160);
DISPLAY INVISIBLE (-1115 3160);
FORCEPROP 1 LASTPIN (-1125 3150) BN 20
J 0
(-1137 3158);
DISPLAY 0.680851 (-1137 3158);
PAINT GREEN (-1137 3158);
FORCEPROP 2 LAST CDS_LIB standard
J 0
(-1075 3150);
PAINT MONO (-1075 3150);
DISPLAY INVISIBLE (-1075 3150);
FORCEPROP 1 LAST BODY_TYPE PLUMBING
J 0
(-1075 3200);
DISPLAY 0.872340 (-1075 3200);
PAINT GREEN (-1075 3200);
DISPLAY INVISIBLE (-1075 3200);
FORCEPROP 1 LAST HDL_TAP TRUE
J 0
(-750 3025);
DISPLAY 0.872340 (-750 3025);
DISPLAY INVISIBLE (-750 3025);
FORCEPROP 1 LAST PATH I66
J 0
(-1077 3150);
DISPLAY 0.872340 (-1077 3150);
PAINT GREEN (-1077 3150);
DISPLAY INVISIBLE (-1077 3150);
FORCEADD TAP..1
(-1075 3250);
FORCEPROP 3 LASTPIN (-1125 3250) SIG_NAME M_F_CPU1_SB_DQ<22>
J 0
(-1115 3260);
DISPLAY 0.659574 (-1115 3260);
PAINT MONO (-1115 3260);
DISPLAY INVISIBLE (-1115 3260);
FORCEPROP 1 LASTPIN (-1125 3250) BN 22
J 0
(-1137 3258);
DISPLAY 0.680851 (-1137 3258);
PAINT GREEN (-1137 3258);
FORCEPROP 2 LAST CDS_LIB standard
J 0
(-1075 3250);
DISPLAY INVISIBLE (-1075 3250);
FORCEPROP 1 LAST BODY_TYPE PLUMBING
J 0
(-1075 3300);
DISPLAY 0.872340 (-1075 3300);
PAINT GREEN (-1075 3300);
DISPLAY INVISIBLE (-1075 3300);
FORCEPROP 1 LAST HDL_TAP TRUE
J 0
(-750 3125);
DISPLAY 0.872340 (-750 3125);
DISPLAY INVISIBLE (-750 3125);
FORCEPROP 1 LAST PATH I67
J 0
(-1077 3250);
DISPLAY 0.872340 (-1077 3250);
PAINT GREEN (-1077 3250);
DISPLAY INVISIBLE (-1077 3250);
FORCEADD TAP..1
(-1075 3200);
FORCEPROP 3 LASTPIN (-1125 3200) SIG_NAME M_F_CPU1_SB_DQ<21>
J 0
(-1115 3210);
DISPLAY 0.659574 (-1115 3210);
PAINT MONO (-1115 3210);
DISPLAY INVISIBLE (-1115 3210);
FORCEPROP 1 LASTPIN (-1125 3200) BN 21
J 0
(-1137 3208);
DISPLAY 0.680851 (-1137 3208);
PAINT GREEN (-1137 3208);
FORCEPROP 2 LAST CDS_LIB standard
J 0
(-1075 3200);
PAINT MONO (-1075 3200);
DISPLAY INVISIBLE (-1075 3200);
FORCEPROP 1 LAST BODY_TYPE PLUMBING
J 0
(-1075 3250);
DISPLAY 0.872340 (-1075 3250);
PAINT GREEN (-1075 3250);
DISPLAY INVISIBLE (-1075 3250);
FORCEPROP 1 LAST HDL_TAP TRUE
J 0
(-750 3075);
DISPLAY 0.872340 (-750 3075);
DISPLAY INVISIBLE (-750 3075);
FORCEPROP 1 LAST PATH I68
J 0
(-1077 3200);
DISPLAY 0.872340 (-1077 3200);
PAINT GREEN (-1077 3200);
DISPLAY INVISIBLE (-1077 3200);
FORCEADD TAP..1
(-1075 3350);
FORCEPROP 3 LASTPIN (-1125 3350) SIG_NAME M_F_CPU1_SB_DQ<24>
J 0
(-1115 3360);
DISPLAY 0.659574 (-1115 3360);
PAINT MONO (-1115 3360);
DISPLAY INVISIBLE (-1115 3360);
FORCEPROP 1 LASTPIN (-1125 3350) BN 24
J 0
(-1137 3358);
DISPLAY 0.680851 (-1137 3358);
PAINT GREEN (-1137 3358);
FORCEPROP 2 LAST CDS_LIB standard
J 0
(-1075 3350);
DISPLAY INVISIBLE (-1075 3350);
FORCEPROP 1 LAST BODY_TYPE PLUMBING
J 0
(-1075 3400);
DISPLAY 0.872340 (-1075 3400);
PAINT GREEN (-1075 3400);
DISPLAY INVISIBLE (-1075 3400);
FORCEPROP 1 LAST HDL_TAP TRUE
J 0
(-750 3225);
DISPLAY 0.872340 (-750 3225);
DISPLAY INVISIBLE (-750 3225);
FORCEPROP 1 LAST PATH I69
J 0
(-1077 3350);
DISPLAY 0.872340 (-1077 3350);
PAINT GREEN (-1077 3350);
DISPLAY INVISIBLE (-1077 3350);
FORCEADD OFFPAGE..1
(-3525 2800);
FORCEPROP 2 LAST $XR7 113 
J 0
(-3897 2836);
DISPLAY 0.638298 (-3897 2836);
PAINT MONO (-3897 2836);
FORCEPROP 2 LAST $XR6 112 
J 0
(-3777 2836);
DISPLAY 0.638298 (-3777 2836);
PAINT MONO (-3777 2836);
FORCEPROP 2 LAST $XR5 111 
J 0
(-4017 2764);
DISPLAY 0.638298 (-4017 2764);
PAINT MONO (-4017 2764);
FORCEPROP 2 LAST $XR4 110 
J 0
(-3897 2764);
DISPLAY 0.638298 (-3897 2764);
PAINT MONO (-3897 2764);
FORCEPROP 2 LAST $XR3 109 
J 0
(-3777 2764);
DISPLAY 0.638298 (-3777 2764);
PAINT MONO (-3777 2764);
FORCEPROP 2 LAST $XR2 107 
J 0
(-4017 2800);
DISPLAY 0.638298 (-4017 2800);
PAINT MONO (-4017 2800);
FORCEPROP 2 LAST $XR1 106 
J 0
(-3897 2800);
DISPLAY 0.638298 (-3897 2800);
PAINT MONO (-3897 2800);
FORCEPROP 2 LAST $XR0 230 
J 0
(-3777 2800);
DISPLAY 0.638298 (-3777 2800);
PAINT MONO (-3777 2800);
FORCEPROP 2 LAST CDS_LIB standard
J 0
(-3525 2800);
PAINT MONO (-3525 2800);
DISPLAY INVISIBLE (-3525 2800);
FORCEPROP 1 LAST OFFPAGE TRUE
J 0
(-3200 2675);
DISPLAY 0.872340 (-3200 2675);
DISPLAY INVISIBLE (-3200 2675);
FORCEPROP 1 LAST COMMENT_BODY TRUE
J 0
(-3400 2700);
DISPLAY 0.872340 (-3400 2700);
PAINT GREEN (-3400 2700);
DISPLAY INVISIBLE (-3400 2700);
FORCEPROP 2 LAST PATH I7
J 0
(-3475 2875);
DISPLAY 1.021277 (-3475 2875);
DISPLAY INVISIBLE (-3475 2875);
FORCEADD TAP..1
(-1075 3300);
FORCEPROP 3 LASTPIN (-1125 3300) SIG_NAME M_F_CPU1_SB_DQ<23>
J 0
(-1115 3310);
DISPLAY 0.659574 (-1115 3310);
PAINT MONO (-1115 3310);
DISPLAY INVISIBLE (-1115 3310);
FORCEPROP 1 LASTPIN (-1125 3300) BN 23
J 0
(-1137 3308);
DISPLAY 0.680851 (-1137 3308);
PAINT GREEN (-1137 3308);
FORCEPROP 2 LAST CDS_LIB standard
J 0
(-1075 3300);
DISPLAY INVISIBLE (-1075 3300);
FORCEPROP 1 LAST BODY_TYPE PLUMBING
J 0
(-1075 3350);
DISPLAY 0.872340 (-1075 3350);
PAINT GREEN (-1075 3350);
DISPLAY INVISIBLE (-1075 3350);
FORCEPROP 1 LAST HDL_TAP TRUE
J 0
(-750 3175);
DISPLAY 0.872340 (-750 3175);
DISPLAY INVISIBLE (-750 3175);
FORCEPROP 1 LAST PATH I70
J 0
(-1077 3300);
DISPLAY 0.872340 (-1077 3300);
PAINT GREEN (-1077 3300);
DISPLAY INVISIBLE (-1077 3300);
FORCEADD TAP..1
(-1075 3400);
FORCEPROP 3 LASTPIN (-1125 3400) SIG_NAME M_F_CPU1_SB_DQ<25>
J 0
(-1115 3410);
DISPLAY 0.659574 (-1115 3410);
PAINT MONO (-1115 3410);
DISPLAY INVISIBLE (-1115 3410);
FORCEPROP 1 LASTPIN (-1125 3400) BN 25
J 0
(-1137 3408);
DISPLAY 0.680851 (-1137 3408);
PAINT GREEN (-1137 3408);
FORCEPROP 2 LAST CDS_LIB standard
J 0
(-1075 3400);
DISPLAY INVISIBLE (-1075 3400);
FORCEPROP 1 LAST BODY_TYPE PLUMBING
J 0
(-1075 3450);
DISPLAY 0.872340 (-1075 3450);
PAINT GREEN (-1075 3450);
DISPLAY INVISIBLE (-1075 3450);
FORCEPROP 1 LAST HDL_TAP TRUE
J 0
(-750 3275);
DISPLAY 0.872340 (-750 3275);
DISPLAY INVISIBLE (-750 3275);
FORCEPROP 1 LAST PATH I71
J 0
(-1077 3400);
DISPLAY 0.872340 (-1077 3400);
PAINT GREEN (-1077 3400);
DISPLAY INVISIBLE (-1077 3400);
FORCEADD TAP..1
(-1075 3450);
FORCEPROP 3 LASTPIN (-1125 3450) SIG_NAME M_F_CPU1_SB_DQ<26>
J 0
(-1115 3460);
DISPLAY 0.659574 (-1115 3460);
PAINT MONO (-1115 3460);
DISPLAY INVISIBLE (-1115 3460);
FORCEPROP 1 LASTPIN (-1125 3450) BN 26
J 0
(-1137 3458);
DISPLAY 0.680851 (-1137 3458);
PAINT GREEN (-1137 3458);
FORCEPROP 2 LAST CDS_LIB standard
J 0
(-1075 3450);
DISPLAY INVISIBLE (-1075 3450);
FORCEPROP 1 LAST BODY_TYPE PLUMBING
J 0
(-1075 3500);
DISPLAY 0.872340 (-1075 3500);
PAINT GREEN (-1075 3500);
DISPLAY INVISIBLE (-1075 3500);
FORCEPROP 1 LAST HDL_TAP TRUE
J 0
(-750 3325);
DISPLAY 0.872340 (-750 3325);
DISPLAY INVISIBLE (-750 3325);
FORCEPROP 1 LAST PATH I72
J 0
(-1077 3450);
DISPLAY 0.872340 (-1077 3450);
PAINT GREEN (-1077 3450);
DISPLAY INVISIBLE (-1077 3450);
FORCEADD TAP..1
(-1075 3500);
FORCEPROP 3 LASTPIN (-1125 3500) SIG_NAME M_F_CPU1_SB_DQ<27>
J 0
(-1115 3510);
DISPLAY 0.659574 (-1115 3510);
PAINT MONO (-1115 3510);
DISPLAY INVISIBLE (-1115 3510);
FORCEPROP 1 LASTPIN (-1125 3500) BN 27
J 0
(-1137 3508);
DISPLAY 0.680851 (-1137 3508);
PAINT GREEN (-1137 3508);
FORCEPROP 2 LAST CDS_LIB standard
J 0
(-1075 3500);
DISPLAY INVISIBLE (-1075 3500);
FORCEPROP 1 LAST BODY_TYPE PLUMBING
J 0
(-1075 3550);
DISPLAY 0.872340 (-1075 3550);
PAINT GREEN (-1075 3550);
DISPLAY INVISIBLE (-1075 3550);
FORCEPROP 1 LAST HDL_TAP TRUE
J 0
(-750 3375);
DISPLAY 0.872340 (-750 3375);
DISPLAY INVISIBLE (-750 3375);
FORCEPROP 1 LAST PATH I73
J 0
(-1077 3500);
DISPLAY 0.872340 (-1077 3500);
PAINT GREEN (-1077 3500);
DISPLAY INVISIBLE (-1077 3500);
FORCEADD TAP..1
(-1075 3600);
FORCEPROP 3 LASTPIN (-1125 3600) SIG_NAME M_F_CPU1_SB_DQ<29>
J 0
(-1115 3610);
DISPLAY 0.659574 (-1115 3610);
PAINT MONO (-1115 3610);
DISPLAY INVISIBLE (-1115 3610);
FORCEPROP 1 LASTPIN (-1125 3600) BN 29
J 0
(-1137 3608);
DISPLAY 0.680851 (-1137 3608);
PAINT GREEN (-1137 3608);
FORCEPROP 2 LAST CDS_LIB standard
J 0
(-1075 3600);
DISPLAY INVISIBLE (-1075 3600);
FORCEPROP 1 LAST BODY_TYPE PLUMBING
J 0
(-1075 3650);
DISPLAY 0.872340 (-1075 3650);
PAINT GREEN (-1075 3650);
DISPLAY INVISIBLE (-1075 3650);
FORCEPROP 1 LAST HDL_TAP TRUE
J 0
(-750 3475);
DISPLAY 0.872340 (-750 3475);
DISPLAY INVISIBLE (-750 3475);
FORCEPROP 1 LAST PATH I74
J 0
(-1077 3600);
DISPLAY 0.872340 (-1077 3600);
PAINT GREEN (-1077 3600);
DISPLAY INVISIBLE (-1077 3600);
FORCEADD TAP..1
(-1075 3550);
FORCEPROP 3 LASTPIN (-1125 3550) SIG_NAME M_F_CPU1_SB_DQ<28>
J 0
(-1115 3560);
DISPLAY 0.659574 (-1115 3560);
PAINT MONO (-1115 3560);
DISPLAY INVISIBLE (-1115 3560);
FORCEPROP 1 LASTPIN (-1125 3550) BN 28
J 0
(-1137 3558);
DISPLAY 0.680851 (-1137 3558);
PAINT GREEN (-1137 3558);
FORCEPROP 2 LAST CDS_LIB standard
J 0
(-1075 3550);
DISPLAY INVISIBLE (-1075 3550);
FORCEPROP 1 LAST BODY_TYPE PLUMBING
J 0
(-1075 3600);
DISPLAY 0.872340 (-1075 3600);
PAINT GREEN (-1075 3600);
DISPLAY INVISIBLE (-1075 3600);
FORCEPROP 1 LAST HDL_TAP TRUE
J 0
(-750 3425);
DISPLAY 0.872340 (-750 3425);
DISPLAY INVISIBLE (-750 3425);
FORCEPROP 1 LAST PATH I75
J 0
(-1077 3550);
DISPLAY 0.872340 (-1077 3550);
PAINT GREEN (-1077 3550);
DISPLAY INVISIBLE (-1077 3550);
FORCEADD TAP..1
(-1075 3700);
FORCEPROP 3 LASTPIN (-1125 3700) SIG_NAME M_F_CPU1_SB_DQ<31>
J 0
(-1115 3710);
DISPLAY 0.659574 (-1115 3710);
PAINT MONO (-1115 3710);
DISPLAY INVISIBLE (-1115 3710);
FORCEPROP 1 LASTPIN (-1125 3700) BN 31
J 0
(-1137 3708);
DISPLAY 0.680851 (-1137 3708);
PAINT GREEN (-1137 3708);
FORCEPROP 2 LAST CDS_LIB standard
J 0
(-1075 3700);
DISPLAY INVISIBLE (-1075 3700);
FORCEPROP 1 LAST BODY_TYPE PLUMBING
J 0
(-1075 3750);
DISPLAY 0.872340 (-1075 3750);
PAINT GREEN (-1075 3750);
DISPLAY INVISIBLE (-1075 3750);
FORCEPROP 1 LAST HDL_TAP TRUE
J 0
(-750 3575);
DISPLAY 0.872340 (-750 3575);
DISPLAY INVISIBLE (-750 3575);
FORCEPROP 1 LAST PATH I76
J 0
(-1077 3700);
DISPLAY 0.872340 (-1077 3700);
PAINT GREEN (-1077 3700);
DISPLAY INVISIBLE (-1077 3700);
FORCEADD TAP..1
(-1075 3650);
FORCEPROP 3 LASTPIN (-1125 3650) SIG_NAME M_F_CPU1_SB_DQ<30>
J 0
(-1115 3660);
DISPLAY 0.659574 (-1115 3660);
PAINT MONO (-1115 3660);
DISPLAY INVISIBLE (-1115 3660);
FORCEPROP 1 LASTPIN (-1125 3650) BN 30
J 0
(-1137 3658);
DISPLAY 0.680851 (-1137 3658);
PAINT GREEN (-1137 3658);
FORCEPROP 2 LAST CDS_LIB standard
J 0
(-1075 3650);
DISPLAY INVISIBLE (-1075 3650);
FORCEPROP 1 LAST BODY_TYPE PLUMBING
J 0
(-1075 3700);
DISPLAY 0.872340 (-1075 3700);
PAINT GREEN (-1075 3700);
DISPLAY INVISIBLE (-1075 3700);
FORCEPROP 1 LAST HDL_TAP TRUE
J 0
(-750 3525);
DISPLAY 0.872340 (-750 3525);
DISPLAY INVISIBLE (-750 3525);
FORCEPROP 1 LAST PATH I77
J 0
(-1077 3650);
DISPLAY 0.872340 (-1077 3650);
PAINT GREEN (-1077 3650);
DISPLAY INVISIBLE (-1077 3650);
FORCEADD TAP..1
(-1075 3800);
FORCEPROP 3 LASTPIN (-1125 3800) SIG_NAME M_F_CPU1_SA_DQ<0>
J 0
(-1115 3810);
DISPLAY 0.659574 (-1115 3810);
PAINT MONO (-1115 3810);
DISPLAY INVISIBLE (-1115 3810);
FORCEPROP 1 LASTPIN (-1125 3800) BN 0
J 0
(-1137 3808);
DISPLAY 0.680851 (-1137 3808);
PAINT GREEN (-1137 3808);
FORCEPROP 2 LAST CDS_LIB standard
J 0
(-1075 3800);
PAINT MONO (-1075 3800);
DISPLAY INVISIBLE (-1075 3800);
FORCEPROP 1 LAST BODY_TYPE PLUMBING
J 0
(-1075 3850);
DISPLAY 0.872340 (-1075 3850);
PAINT GREEN (-1075 3850);
DISPLAY INVISIBLE (-1075 3850);
FORCEPROP 1 LAST HDL_TAP TRUE
J 0
(-750 3675);
DISPLAY 0.872340 (-750 3675);
DISPLAY INVISIBLE (-750 3675);
FORCEPROP 1 LAST PATH I78
J 0
(-1077 3800);
DISPLAY 0.872340 (-1077 3800);
PAINT GREEN (-1077 3800);
DISPLAY INVISIBLE (-1077 3800);
FORCEADD TAP..1
(-1075 3850);
FORCEPROP 3 LASTPIN (-1125 3850) SIG_NAME M_F_CPU1_SA_DQ<1>
J 0
(-1115 3860);
DISPLAY 0.659574 (-1115 3860);
PAINT MONO (-1115 3860);
DISPLAY INVISIBLE (-1115 3860);
FORCEPROP 1 LASTPIN (-1125 3850) BN 1
J 0
(-1137 3858);
DISPLAY 0.680851 (-1137 3858);
PAINT GREEN (-1137 3858);
FORCEPROP 2 LAST CDS_LIB standard
J 0
(-1075 3850);
PAINT MONO (-1075 3850);
DISPLAY INVISIBLE (-1075 3850);
FORCEPROP 1 LAST BODY_TYPE PLUMBING
J 0
(-1075 3900);
DISPLAY 0.872340 (-1075 3900);
PAINT GREEN (-1075 3900);
DISPLAY INVISIBLE (-1075 3900);
FORCEPROP 1 LAST HDL_TAP TRUE
J 0
(-750 3725);
DISPLAY 0.872340 (-750 3725);
DISPLAY INVISIBLE (-750 3725);
FORCEPROP 1 LAST PATH I79
J 0
(-1077 3850);
DISPLAY 0.872340 (-1077 3850);
PAINT GREEN (-1077 3850);
DISPLAY INVISIBLE (-1077 3850);
FORCEADD OFFPAGE..1
(-3650 3000);
FORCEPROP 2 LAST $XR1 109 
J 0
(-3991 3000);
DISPLAY 0.638298 (-3991 3000);
PAINT MONO (-3991 3000);
FORCEPROP 2 LAST $XR0 56 
J 0
(-3871 3000);
DISPLAY 0.638298 (-3871 3000);
PAINT MONO (-3871 3000);
FORCEPROP 2 LAST CDS_LIB standard
J 0
(-3650 3000);
PAINT MONO (-3650 3000);
DISPLAY INVISIBLE (-3650 3000);
FORCEPROP 1 LAST OFFPAGE TRUE
J 0
(-3325 2875);
DISPLAY 0.872340 (-3325 2875);
DISPLAY INVISIBLE (-3325 2875);
FORCEPROP 1 LAST COMMENT_BODY TRUE
J 0
(-3525 2900);
DISPLAY 0.872340 (-3525 2900);
PAINT GREEN (-3525 2900);
DISPLAY INVISIBLE (-3525 2900);
FORCEPROP 2 LAST PATH I8
J 0
(-3600 3075);
DISPLAY 1.021277 (-3600 3075);
DISPLAY INVISIBLE (-3600 3075);
FORCEADD TAP..1
(-1075 3950);
FORCEPROP 3 LASTPIN (-1125 3950) SIG_NAME M_F_CPU1_SA_DQ<3>
J 0
(-1115 3960);
DISPLAY 0.659574 (-1115 3960);
PAINT MONO (-1115 3960);
DISPLAY INVISIBLE (-1115 3960);
FORCEPROP 1 LASTPIN (-1125 3950) BN 3
J 0
(-1137 3958);
DISPLAY 0.680851 (-1137 3958);
PAINT GREEN (-1137 3958);
FORCEPROP 2 LAST CDS_LIB standard
J 0
(-1075 3950);
PAINT MONO (-1075 3950);
DISPLAY INVISIBLE (-1075 3950);
FORCEPROP 1 LAST BODY_TYPE PLUMBING
J 0
(-1075 4000);
DISPLAY 0.872340 (-1075 4000);
PAINT GREEN (-1075 4000);
DISPLAY INVISIBLE (-1075 4000);
FORCEPROP 1 LAST HDL_TAP TRUE
J 0
(-750 3825);
DISPLAY 0.872340 (-750 3825);
DISPLAY INVISIBLE (-750 3825);
FORCEPROP 1 LAST PATH I80
J 0
(-1077 3950);
DISPLAY 0.872340 (-1077 3950);
PAINT GREEN (-1077 3950);
DISPLAY INVISIBLE (-1077 3950);
FORCEADD TAP..1
(-1075 3900);
FORCEPROP 3 LASTPIN (-1125 3900) SIG_NAME M_F_CPU1_SA_DQ<2>
J 0
(-1115 3910);
DISPLAY 0.659574 (-1115 3910);
PAINT MONO (-1115 3910);
DISPLAY INVISIBLE (-1115 3910);
FORCEPROP 1 LASTPIN (-1125 3900) BN 2
J 0
(-1137 3908);
DISPLAY 0.680851 (-1137 3908);
PAINT GREEN (-1137 3908);
FORCEPROP 2 LAST CDS_LIB standard
J 0
(-1075 3900);
PAINT MONO (-1075 3900);
DISPLAY INVISIBLE (-1075 3900);
FORCEPROP 1 LAST BODY_TYPE PLUMBING
J 0
(-1075 3950);
DISPLAY 0.872340 (-1075 3950);
PAINT GREEN (-1075 3950);
DISPLAY INVISIBLE (-1075 3950);
FORCEPROP 1 LAST HDL_TAP TRUE
J 0
(-750 3775);
DISPLAY 0.872340 (-750 3775);
DISPLAY INVISIBLE (-750 3775);
FORCEPROP 1 LAST PATH I81
J 0
(-1077 3900);
DISPLAY 0.872340 (-1077 3900);
PAINT GREEN (-1077 3900);
DISPLAY INVISIBLE (-1077 3900);
FORCEADD TAP..1
(-1075 4000);
FORCEPROP 3 LASTPIN (-1125 4000) SIG_NAME M_F_CPU1_SA_DQ<4>
J 0
(-1115 4010);
DISPLAY 0.659574 (-1115 4010);
PAINT MONO (-1115 4010);
DISPLAY INVISIBLE (-1115 4010);
FORCEPROP 1 LASTPIN (-1125 4000) BN 4
J 0
(-1137 4008);
DISPLAY 0.680851 (-1137 4008);
PAINT GREEN (-1137 4008);
FORCEPROP 2 LAST CDS_LIB standard
J 0
(-1075 4000);
PAINT MONO (-1075 4000);
DISPLAY INVISIBLE (-1075 4000);
FORCEPROP 1 LAST BODY_TYPE PLUMBING
J 0
(-1075 4050);
DISPLAY 0.872340 (-1075 4050);
PAINT GREEN (-1075 4050);
DISPLAY INVISIBLE (-1075 4050);
FORCEPROP 1 LAST HDL_TAP TRUE
J 0
(-750 3875);
DISPLAY 0.872340 (-750 3875);
DISPLAY INVISIBLE (-750 3875);
FORCEPROP 1 LAST PATH I82
J 0
(-1077 4000);
DISPLAY 0.872340 (-1077 4000);
PAINT GREEN (-1077 4000);
DISPLAY INVISIBLE (-1077 4000);
FORCEADD TAP..1
(-1075 4100);
FORCEPROP 3 LASTPIN (-1125 4100) SIG_NAME M_F_CPU1_SA_DQ<6>
J 0
(-1115 4110);
DISPLAY 0.659574 (-1115 4110);
PAINT MONO (-1115 4110);
DISPLAY INVISIBLE (-1115 4110);
FORCEPROP 1 LASTPIN (-1125 4100) BN 6
J 0
(-1137 4108);
DISPLAY 0.680851 (-1137 4108);
PAINT GREEN (-1137 4108);
FORCEPROP 2 LAST CDS_LIB standard
J 0
(-1075 4100);
PAINT MONO (-1075 4100);
DISPLAY INVISIBLE (-1075 4100);
FORCEPROP 1 LAST BODY_TYPE PLUMBING
J 0
(-1075 4150);
DISPLAY 0.872340 (-1075 4150);
PAINT GREEN (-1075 4150);
DISPLAY INVISIBLE (-1075 4150);
FORCEPROP 1 LAST HDL_TAP TRUE
J 0
(-750 3975);
DISPLAY 0.872340 (-750 3975);
DISPLAY INVISIBLE (-750 3975);
FORCEPROP 1 LAST PATH I83
J 0
(-1077 4100);
DISPLAY 0.872340 (-1077 4100);
PAINT GREEN (-1077 4100);
DISPLAY INVISIBLE (-1077 4100);
FORCEADD TAP..1
(-1075 4050);
FORCEPROP 3 LASTPIN (-1125 4050) SIG_NAME M_F_CPU1_SA_DQ<5>
J 0
(-1115 4060);
DISPLAY 0.659574 (-1115 4060);
PAINT MONO (-1115 4060);
DISPLAY INVISIBLE (-1115 4060);
FORCEPROP 1 LASTPIN (-1125 4050) BN 5
J 0
(-1137 4058);
DISPLAY 0.680851 (-1137 4058);
PAINT GREEN (-1137 4058);
FORCEPROP 2 LAST CDS_LIB standard
J 0
(-1075 4050);
PAINT MONO (-1075 4050);
DISPLAY INVISIBLE (-1075 4050);
FORCEPROP 1 LAST BODY_TYPE PLUMBING
J 0
(-1075 4100);
DISPLAY 0.872340 (-1075 4100);
PAINT GREEN (-1075 4100);
DISPLAY INVISIBLE (-1075 4100);
FORCEPROP 1 LAST HDL_TAP TRUE
J 0
(-750 3925);
DISPLAY 0.872340 (-750 3925);
DISPLAY INVISIBLE (-750 3925);
FORCEPROP 1 LAST PATH I84
J 0
(-1077 4050);
DISPLAY 0.872340 (-1077 4050);
PAINT GREEN (-1077 4050);
DISPLAY INVISIBLE (-1077 4050);
FORCEADD TAP..1
(-1075 4150);
FORCEPROP 3 LASTPIN (-1125 4150) SIG_NAME M_F_CPU1_SA_DQ<7>
J 0
(-1115 4160);
DISPLAY 0.659574 (-1115 4160);
PAINT MONO (-1115 4160);
DISPLAY INVISIBLE (-1115 4160);
FORCEPROP 1 LASTPIN (-1125 4150) BN 7
J 0
(-1137 4158);
DISPLAY 0.680851 (-1137 4158);
PAINT GREEN (-1137 4158);
FORCEPROP 2 LAST CDS_LIB standard
J 0
(-1075 4150);
PAINT MONO (-1075 4150);
DISPLAY INVISIBLE (-1075 4150);
FORCEPROP 1 LAST BODY_TYPE PLUMBING
J 0
(-1075 4200);
DISPLAY 0.872340 (-1075 4200);
PAINT GREEN (-1075 4200);
DISPLAY INVISIBLE (-1075 4200);
FORCEPROP 1 LAST HDL_TAP TRUE
J 0
(-750 4025);
DISPLAY 0.872340 (-750 4025);
DISPLAY INVISIBLE (-750 4025);
FORCEPROP 1 LAST PATH I85
J 0
(-1077 4150);
DISPLAY 0.872340 (-1077 4150);
PAINT GREEN (-1077 4150);
DISPLAY INVISIBLE (-1077 4150);
FORCEADD TAP..1
(-1075 4250);
FORCEPROP 3 LASTPIN (-1125 4250) SIG_NAME M_F_CPU1_SA_DQ<9>
J 0
(-1115 4260);
DISPLAY 0.659574 (-1115 4260);
PAINT MONO (-1115 4260);
DISPLAY INVISIBLE (-1115 4260);
FORCEPROP 1 LASTPIN (-1125 4250) BN 9
J 0
(-1137 4258);
DISPLAY 0.680851 (-1137 4258);
PAINT GREEN (-1137 4258);
FORCEPROP 2 LAST CDS_LIB standard
J 0
(-1075 4250);
PAINT MONO (-1075 4250);
DISPLAY INVISIBLE (-1075 4250);
FORCEPROP 1 LAST BODY_TYPE PLUMBING
J 0
(-1075 4300);
DISPLAY 0.872340 (-1075 4300);
PAINT GREEN (-1075 4300);
DISPLAY INVISIBLE (-1075 4300);
FORCEPROP 1 LAST HDL_TAP TRUE
J 0
(-750 4125);
DISPLAY 0.872340 (-750 4125);
DISPLAY INVISIBLE (-750 4125);
FORCEPROP 1 LAST PATH I86
J 0
(-1077 4250);
DISPLAY 0.872340 (-1077 4250);
PAINT GREEN (-1077 4250);
DISPLAY INVISIBLE (-1077 4250);
FORCEADD TAP..1
(-1075 4200);
FORCEPROP 3 LASTPIN (-1125 4200) SIG_NAME M_F_CPU1_SA_DQ<8>
J 0
(-1115 4210);
DISPLAY 0.659574 (-1115 4210);
PAINT MONO (-1115 4210);
DISPLAY INVISIBLE (-1115 4210);
FORCEPROP 1 LASTPIN (-1125 4200) BN 8
J 0
(-1137 4208);
DISPLAY 0.680851 (-1137 4208);
PAINT GREEN (-1137 4208);
FORCEPROP 2 LAST CDS_LIB standard
J 0
(-1075 4200);
PAINT MONO (-1075 4200);
DISPLAY INVISIBLE (-1075 4200);
FORCEPROP 1 LAST BODY_TYPE PLUMBING
J 0
(-1075 4250);
DISPLAY 0.872340 (-1075 4250);
PAINT GREEN (-1075 4250);
DISPLAY INVISIBLE (-1075 4250);
FORCEPROP 1 LAST HDL_TAP TRUE
J 0
(-750 4075);
DISPLAY 0.872340 (-750 4075);
DISPLAY INVISIBLE (-750 4075);
FORCEPROP 1 LAST PATH I87
J 0
(-1077 4200);
DISPLAY 0.872340 (-1077 4200);
PAINT GREEN (-1077 4200);
DISPLAY INVISIBLE (-1077 4200);
FORCEADD TAP..1
(-1075 4300);
FORCEPROP 3 LASTPIN (-1125 4300) SIG_NAME M_F_CPU1_SA_DQ<10>
J 0
(-1115 4310);
DISPLAY 0.659574 (-1115 4310);
PAINT MONO (-1115 4310);
DISPLAY INVISIBLE (-1115 4310);
FORCEPROP 1 LASTPIN (-1125 4300) BN 10
J 0
(-1137 4308);
DISPLAY 0.680851 (-1137 4308);
PAINT GREEN (-1137 4308);
FORCEPROP 2 LAST CDS_LIB standard
J 0
(-1075 4300);
PAINT MONO (-1075 4300);
DISPLAY INVISIBLE (-1075 4300);
FORCEPROP 1 LAST BODY_TYPE PLUMBING
J 0
(-1075 4350);
DISPLAY 0.872340 (-1075 4350);
PAINT GREEN (-1075 4350);
DISPLAY INVISIBLE (-1075 4350);
FORCEPROP 1 LAST HDL_TAP TRUE
J 0
(-750 4175);
DISPLAY 0.872340 (-750 4175);
DISPLAY INVISIBLE (-750 4175);
FORCEPROP 1 LAST PATH I88
J 0
(-1077 4300);
DISPLAY 0.872340 (-1077 4300);
PAINT GREEN (-1077 4300);
DISPLAY INVISIBLE (-1077 4300);
FORCEADD TAP..1
(-1075 4350);
FORCEPROP 3 LASTPIN (-1125 4350) SIG_NAME M_F_CPU1_SA_DQ<11>
J 0
(-1115 4360);
DISPLAY 0.659574 (-1115 4360);
PAINT MONO (-1115 4360);
DISPLAY INVISIBLE (-1115 4360);
FORCEPROP 1 LASTPIN (-1125 4350) BN 11
J 0
(-1137 4358);
DISPLAY 0.680851 (-1137 4358);
PAINT GREEN (-1137 4358);
FORCEPROP 2 LAST CDS_LIB standard
J 0
(-1075 4350);
PAINT MONO (-1075 4350);
DISPLAY INVISIBLE (-1075 4350);
FORCEPROP 1 LAST BODY_TYPE PLUMBING
J 0
(-1075 4400);
DISPLAY 0.872340 (-1075 4400);
PAINT GREEN (-1075 4400);
DISPLAY INVISIBLE (-1075 4400);
FORCEPROP 1 LAST HDL_TAP TRUE
J 0
(-750 4225);
DISPLAY 0.872340 (-750 4225);
DISPLAY INVISIBLE (-750 4225);
FORCEPROP 1 LAST PATH I89
J 0
(-1077 4350);
DISPLAY 0.872340 (-1077 4350);
PAINT GREEN (-1077 4350);
DISPLAY INVISIBLE (-1077 4350);
FORCEADD UNIVERSAL_GND..1
(-2500 975);
FORCEPROP 3 LASTPIN (-2500 1025) SIG_NAME GND\g
J 0
(-2490 1035);
DISPLAY 0.659574 (-2490 1035);
PAINT MONO (-2490 1035);
DISPLAY INVISIBLE (-2490 1035);
FORCEPROP 1 LAST PATH I9
J 0
(-2425 975);
DISPLAY 0.872340 (-2425 975);
PAINT AQUA (-2425 975);
DISPLAY INVISIBLE (-2425 975);
FORCEPROP 1 LAST HDL_POWER GND
J 1
(-2475 900);
DISPLAY 0.872340 (-2475 900);
PAINT GREEN (-2475 900);
DISPLAY INVISIBLE (-2475 900);
FORCEPROP 2 LAST CDS_LIB logical_power
J 0
(-2500 975);
PAINT MONO (-2500 975);
DISPLAY INVISIBLE (-2500 975);
FORCEADD TAP..1
(-1075 4400);
FORCEPROP 3 LASTPIN (-1125 4400) SIG_NAME M_F_CPU1_SA_DQ<12>
J 0
(-1115 4410);
DISPLAY 0.659574 (-1115 4410);
PAINT MONO (-1115 4410);
DISPLAY INVISIBLE (-1115 4410);
FORCEPROP 1 LASTPIN (-1125 4400) BN 12
J 0
(-1137 4408);
DISPLAY 0.680851 (-1137 4408);
PAINT GREEN (-1137 4408);
FORCEPROP 2 LAST CDS_LIB standard
J 0
(-1075 4400);
PAINT MONO (-1075 4400);
DISPLAY INVISIBLE (-1075 4400);
FORCEPROP 1 LAST BODY_TYPE PLUMBING
J 0
(-1075 4450);
DISPLAY 0.872340 (-1075 4450);
PAINT GREEN (-1075 4450);
DISPLAY INVISIBLE (-1075 4450);
FORCEPROP 1 LAST HDL_TAP TRUE
J 0
(-750 4275);
DISPLAY 0.872340 (-750 4275);
DISPLAY INVISIBLE (-750 4275);
FORCEPROP 1 LAST PATH I90
J 0
(-1077 4400);
DISPLAY 0.872340 (-1077 4400);
PAINT GREEN (-1077 4400);
DISPLAY INVISIBLE (-1077 4400);
FORCEADD TAP..1
(-1075 4500);
FORCEPROP 3 LASTPIN (-1125 4500) SIG_NAME M_F_CPU1_SA_DQ<14>
J 0
(-1115 4510);
DISPLAY 0.659574 (-1115 4510);
PAINT MONO (-1115 4510);
DISPLAY INVISIBLE (-1115 4510);
FORCEPROP 1 LASTPIN (-1125 4500) BN 14
J 0
(-1137 4508);
DISPLAY 0.680851 (-1137 4508);
PAINT GREEN (-1137 4508);
FORCEPROP 2 LAST CDS_LIB standard
J 0
(-1075 4500);
PAINT MONO (-1075 4500);
DISPLAY INVISIBLE (-1075 4500);
FORCEPROP 1 LAST BODY_TYPE PLUMBING
J 0
(-1075 4550);
DISPLAY 0.872340 (-1075 4550);
PAINT GREEN (-1075 4550);
DISPLAY INVISIBLE (-1075 4550);
FORCEPROP 1 LAST HDL_TAP TRUE
J 0
(-750 4375);
DISPLAY 0.872340 (-750 4375);
DISPLAY INVISIBLE (-750 4375);
FORCEPROP 1 LAST PATH I91
J 0
(-1077 4500);
DISPLAY 0.872340 (-1077 4500);
PAINT GREEN (-1077 4500);
DISPLAY INVISIBLE (-1077 4500);
FORCEADD TAP..1
(-1075 4450);
FORCEPROP 3 LASTPIN (-1125 4450) SIG_NAME M_F_CPU1_SA_DQ<13>
J 0
(-1115 4460);
DISPLAY 0.659574 (-1115 4460);
PAINT MONO (-1115 4460);
DISPLAY INVISIBLE (-1115 4460);
FORCEPROP 1 LASTPIN (-1125 4450) BN 13
J 0
(-1137 4458);
DISPLAY 0.680851 (-1137 4458);
PAINT GREEN (-1137 4458);
FORCEPROP 2 LAST CDS_LIB standard
J 0
(-1075 4450);
PAINT MONO (-1075 4450);
DISPLAY INVISIBLE (-1075 4450);
FORCEPROP 1 LAST BODY_TYPE PLUMBING
J 0
(-1075 4500);
DISPLAY 0.872340 (-1075 4500);
PAINT GREEN (-1075 4500);
DISPLAY INVISIBLE (-1075 4500);
FORCEPROP 1 LAST HDL_TAP TRUE
J 0
(-750 4325);
DISPLAY 0.872340 (-750 4325);
DISPLAY INVISIBLE (-750 4325);
FORCEPROP 1 LAST PATH I92
J 0
(-1077 4450);
DISPLAY 0.872340 (-1077 4450);
PAINT GREEN (-1077 4450);
DISPLAY INVISIBLE (-1077 4450);
FORCEADD TAP..1
(-1075 4550);
FORCEPROP 3 LASTPIN (-1125 4550) SIG_NAME M_F_CPU1_SA_DQ<15>
J 0
(-1115 4560);
DISPLAY 0.659574 (-1115 4560);
PAINT MONO (-1115 4560);
DISPLAY INVISIBLE (-1115 4560);
FORCEPROP 1 LASTPIN (-1125 4550) BN 15
J 0
(-1137 4558);
DISPLAY 0.680851 (-1137 4558);
PAINT GREEN (-1137 4558);
FORCEPROP 2 LAST CDS_LIB standard
J 0
(-1075 4550);
PAINT MONO (-1075 4550);
DISPLAY INVISIBLE (-1075 4550);
FORCEPROP 1 LAST BODY_TYPE PLUMBING
J 0
(-1075 4600);
DISPLAY 0.872340 (-1075 4600);
PAINT GREEN (-1075 4600);
DISPLAY INVISIBLE (-1075 4600);
FORCEPROP 1 LAST HDL_TAP TRUE
J 0
(-750 4425);
DISPLAY 0.872340 (-750 4425);
DISPLAY INVISIBLE (-750 4425);
FORCEPROP 1 LAST PATH I93
J 0
(-1077 4550);
DISPLAY 0.872340 (-1077 4550);
PAINT GREEN (-1077 4550);
DISPLAY INVISIBLE (-1077 4550);
FORCEADD TAP..1
(-1075 4600);
FORCEPROP 3 LASTPIN (-1125 4600) SIG_NAME M_F_CPU1_SA_DQ<16>
J 0
(-1115 4610);
DISPLAY 0.659574 (-1115 4610);
PAINT MONO (-1115 4610);
DISPLAY INVISIBLE (-1115 4610);
FORCEPROP 1 LASTPIN (-1125 4600) BN 16
J 0
(-1137 4608);
DISPLAY 0.680851 (-1137 4608);
PAINT GREEN (-1137 4608);
FORCEPROP 2 LAST CDS_LIB standard
J 0
(-1075 4600);
PAINT MONO (-1075 4600);
DISPLAY INVISIBLE (-1075 4600);
FORCEPROP 1 LAST BODY_TYPE PLUMBING
J 0
(-1075 4650);
DISPLAY 0.872340 (-1075 4650);
PAINT GREEN (-1075 4650);
DISPLAY INVISIBLE (-1075 4650);
FORCEPROP 1 LAST HDL_TAP TRUE
J 0
(-750 4475);
DISPLAY 0.872340 (-750 4475);
DISPLAY INVISIBLE (-750 4475);
FORCEPROP 1 LAST PATH I94
J 0
(-1077 4600);
DISPLAY 0.872340 (-1077 4600);
PAINT GREEN (-1077 4600);
DISPLAY INVISIBLE (-1077 4600);
FORCEADD TAP..1
(-1075 4650);
FORCEPROP 3 LASTPIN (-1125 4650) SIG_NAME M_F_CPU1_SA_DQ<17>
J 0
(-1115 4660);
DISPLAY 0.659574 (-1115 4660);
PAINT MONO (-1115 4660);
DISPLAY INVISIBLE (-1115 4660);
FORCEPROP 1 LASTPIN (-1125 4650) BN 17
J 0
(-1137 4658);
DISPLAY 0.680851 (-1137 4658);
PAINT GREEN (-1137 4658);
FORCEPROP 2 LAST CDS_LIB standard
J 0
(-1075 4650);
PAINT MONO (-1075 4650);
DISPLAY INVISIBLE (-1075 4650);
FORCEPROP 1 LAST BODY_TYPE PLUMBING
J 0
(-1075 4700);
DISPLAY 0.872340 (-1075 4700);
PAINT GREEN (-1075 4700);
DISPLAY INVISIBLE (-1075 4700);
FORCEPROP 1 LAST HDL_TAP TRUE
J 0
(-750 4525);
DISPLAY 0.872340 (-750 4525);
DISPLAY INVISIBLE (-750 4525);
FORCEPROP 1 LAST PATH I95
J 0
(-1077 4650);
DISPLAY 0.872340 (-1077 4650);
PAINT GREEN (-1077 4650);
DISPLAY INVISIBLE (-1077 4650);
FORCEADD TAP..1
(-1075 4750);
FORCEPROP 3 LASTPIN (-1125 4750) SIG_NAME M_F_CPU1_SA_DQ<19>
J 0
(-1115 4760);
DISPLAY 0.659574 (-1115 4760);
PAINT MONO (-1115 4760);
DISPLAY INVISIBLE (-1115 4760);
FORCEPROP 1 LASTPIN (-1125 4750) BN 19
J 0
(-1137 4758);
DISPLAY 0.680851 (-1137 4758);
PAINT GREEN (-1137 4758);
FORCEPROP 2 LAST CDS_LIB standard
J 0
(-1075 4750);
PAINT MONO (-1075 4750);
DISPLAY INVISIBLE (-1075 4750);
FORCEPROP 1 LAST BODY_TYPE PLUMBING
J 0
(-1075 4800);
DISPLAY 0.872340 (-1075 4800);
PAINT GREEN (-1075 4800);
DISPLAY INVISIBLE (-1075 4800);
FORCEPROP 1 LAST HDL_TAP TRUE
J 0
(-750 4625);
DISPLAY 0.872340 (-750 4625);
DISPLAY INVISIBLE (-750 4625);
FORCEPROP 1 LAST PATH I96
J 0
(-1077 4750);
DISPLAY 0.872340 (-1077 4750);
PAINT GREEN (-1077 4750);
DISPLAY INVISIBLE (-1077 4750);
FORCEADD TAP..1
(-1075 4700);
FORCEPROP 3 LASTPIN (-1125 4700) SIG_NAME M_F_CPU1_SA_DQ<18>
J 0
(-1115 4710);
DISPLAY 0.659574 (-1115 4710);
PAINT MONO (-1115 4710);
DISPLAY INVISIBLE (-1115 4710);
FORCEPROP 1 LASTPIN (-1125 4700) BN 18
J 0
(-1137 4708);
DISPLAY 0.680851 (-1137 4708);
PAINT GREEN (-1137 4708);
FORCEPROP 2 LAST CDS_LIB standard
J 0
(-1075 4700);
PAINT MONO (-1075 4700);
DISPLAY INVISIBLE (-1075 4700);
FORCEPROP 1 LAST BODY_TYPE PLUMBING
J 0
(-1075 4750);
DISPLAY 0.872340 (-1075 4750);
PAINT GREEN (-1075 4750);
DISPLAY INVISIBLE (-1075 4750);
FORCEPROP 1 LAST HDL_TAP TRUE
J 0
(-750 4575);
DISPLAY 0.872340 (-750 4575);
DISPLAY INVISIBLE (-750 4575);
FORCEPROP 1 LAST PATH I97
J 0
(-1077 4700);
DISPLAY 0.872340 (-1077 4700);
PAINT GREEN (-1077 4700);
DISPLAY INVISIBLE (-1077 4700);
FORCEADD TAP..1
(-1075 4800);
FORCEPROP 3 LASTPIN (-1125 4800) SIG_NAME M_F_CPU1_SA_DQ<20>
J 0
(-1115 4810);
DISPLAY 0.659574 (-1115 4810);
PAINT MONO (-1115 4810);
DISPLAY INVISIBLE (-1115 4810);
FORCEPROP 1 LASTPIN (-1125 4800) BN 20
J 0
(-1137 4808);
DISPLAY 0.680851 (-1137 4808);
PAINT GREEN (-1137 4808);
FORCEPROP 2 LAST CDS_LIB standard
J 0
(-1075 4800);
PAINT MONO (-1075 4800);
DISPLAY INVISIBLE (-1075 4800);
FORCEPROP 1 LAST BODY_TYPE PLUMBING
J 0
(-1075 4850);
DISPLAY 0.872340 (-1075 4850);
PAINT GREEN (-1075 4850);
DISPLAY INVISIBLE (-1075 4850);
FORCEPROP 1 LAST HDL_TAP TRUE
J 0
(-750 4675);
DISPLAY 0.872340 (-750 4675);
DISPLAY INVISIBLE (-750 4675);
FORCEPROP 1 LAST PATH I98
J 0
(-1077 4800);
DISPLAY 0.872340 (-1077 4800);
PAINT GREEN (-1077 4800);
DISPLAY INVISIBLE (-1077 4800);
FORCEADD TAP..1
(-1075 4850);
FORCEPROP 3 LASTPIN (-1125 4850) SIG_NAME M_F_CPU1_SA_DQ<21>
J 0
(-1115 4860);
DISPLAY 0.659574 (-1115 4860);
PAINT MONO (-1115 4860);
DISPLAY INVISIBLE (-1115 4860);
FORCEPROP 1 LASTPIN (-1125 4850) BN 21
J 0
(-1137 4858);
DISPLAY 0.680851 (-1137 4858);
PAINT GREEN (-1137 4858);
FORCEPROP 2 LAST CDS_LIB standard
J 0
(-1075 4850);
PAINT MONO (-1075 4850);
DISPLAY INVISIBLE (-1075 4850);
FORCEPROP 1 LAST BODY_TYPE PLUMBING
J 0
(-1075 4900);
DISPLAY 0.872340 (-1075 4900);
PAINT GREEN (-1075 4900);
DISPLAY INVISIBLE (-1075 4900);
FORCEPROP 1 LAST HDL_TAP TRUE
J 0
(-750 4725);
DISPLAY 0.872340 (-750 4725);
DISPLAY INVISIBLE (-750 4725);
FORCEPROP 1 LAST PATH I99
J 0
(-1077 4850);
DISPLAY 0.872340 (-1077 4850);
PAINT GREEN (-1077 4850);
DISPLAY INVISIBLE (-1077 4850);
FORCEADD CAD_NOTE..1
(775 900);
FORCEPROP 0 LAST S1 PLACE THE BYPASS CAPS CLOSE TO DIMM
J 0
(650 775);
DISPLAY 1.021277 (650 775);
PAINT WHITE (650 775);
FORCEPROP 2 LAST CDS_LIB logical_power
J 0
(775 900);
PAINT MONO (775 900);
DISPLAY INVISIBLE (775 900);
FORCEPROP 1 LAST COMMENT_BODY TRUE
J 0
(800 1000);
DISPLAY 0.978723 (800 1000);
DISPLAY INVISIBLE (800 1000);
FORCEADD QUANTA_TITLE_BLOCK_C..1
(5250 -400);
FORCEPROP 0 LAST CDS_CON_LAST_MODIFIED Fri Aug 25 14:01:29 2023
J 0
(3365 -385);
PAINT MONO (3365 -385);
DISPLAY INVISIBLE (3365 -385);
FORCEPROP 2 LAST CUSTOM_TXT_CDS <XR_PAGE_TITLE>
J 0
(-2640 4850);
DISPLAY 0.638298 (-2640 4850);
PAINT PINK (-2640 4850);
DISPLAY INVISIBLE (-2640 4850);
FORCEPROP 2 LAST CUSTOM_TXT_CDS <CON_PAGE_NUM> OF <CON_TOTAL_PAGES>
J 0
(4804 -382);
DISPLAY 0.978723 (4804 -382);
FORCEPROP 2 LAST CUSTOM_TXT_CDS <Q_REV>
J 0
(5066 -297);
DISPLAY 1.212766 (5066 -297);
FORCEPROP 2 LAST CUSTOM_TXT_CDS <Q_NUMBER>
J 0
(3847 -297);
DISPLAY 1.212766 (3847 -297);
FORCEPROP 2 LAST CUSTOM_TXT_CDS <Q_PROJ>
J 0
(2868 -298);
DISPLAY 1.212766 (2868 -298);
FORCEPROP 2 LAST CUSTOM_TXT_CDS <NAME_2>
J 0
(2075 -350);
FORCEPROP 2 LAST CUSTOM_TXT_CDS <NAME_1>
J 0
(2075 -225);
FORCEPROP 2 LAST CUSTOM_TXT_CDS <CON_LAST_MODIFIED>
J 0
(3365 -385);
DISPLAY 0.978723 (3365 -385);
FORCEPROP 1 LAST Q_TITLE DDR5 - CPU1 CHF DIMM1(YELLOW)
J 0
(-4116 -374);
DISPLAY 2.446809 (-4116 -374);
PAINT GREEN (-4116 -374);
FORCEPROP 1 LAST Q_DEPT 
J 1
(1487 -351);
DISPLAY 1.957447 (1487 -351);
PAINT GREEN (1487 -351);
FORCEPROP 2 LAST CDS_XR_PAGE_TITLE CR-108 : @S9S_MB_2U_LIB.S9S_MB_2U(SCH_1):PAGE108
J 0
(-2640 4850);
DISPLAY 0.638298 (-2640 4850);
PAINT PINK (-2640 4850);
DISPLAY INVISIBLE (-2640 4850);
FORCEPROP 1 LAST COMMENT_BODY TRUE
J 0
(5262 -413);
DISPLAY 0.978723 (5262 -413);
PAINT GREEN (5262 -413);
DISPLAY INVISIBLE (5262 -413);
FORCEPROP 2 LAST PAGE_BORDER TRUE
J 0
(-2640 4850);
DISPLAY 0.638298 (-2640 4850);
PAINT PINK (-2640 4850);
DISPLAY INVISIBLE (-2640 4850);
FORCEPROP 1 LAST CDS_LMAN_SYM_OUTLINE -9475,6775,100,-125
J 0
(5250 -400);
DISPLAY 0.468085 (5250 -400);
PAINT GREEN (5250 -400);
DISPLAY INVISIBLE (5250 -400);
FORCEPROP 2 LAST CDS_LIB pure_quanta
J 0
(5250 -400);
PAINT MONO (5250 -400);
DISPLAY INVISIBLE (5250 -400);
WIRE 17 -1 (-1025 5375)(-300 5375);
FORCEPROP 2 LAST SIG_NAME M_F_CPU1_SA_DQ<31:0>
J 0
(-960 5385);
DISPLAY 0.680851 (-960 5385);
PAINT WHITE (-960 5385);
WIRE 17 -1 (-3600 3975)(-2775 3975);
FORCEPROP 2 LAST SIG_NAME M_F_CPU1_SA_CB<7:0>
J 0
(-3510 3985);
DISPLAY 0.680851 (-3510 3985);
PAINT WHITE (-3510 3985);
WIRE 17 -1 (-2775 3825)(-2775 3875);
WIRE 17 -1 (-2775 3775)(-2775 3825);
WIRE 17 -1 (-2775 3875)(-2775 3925);
WIRE 17 -1 (-2775 3925)(-2775 3975);
WIRE 17 -1 (-2775 3725)(-2775 3775);
WIRE 17 -1 (-2775 3675)(-2775 3725);
WIRE 17 -1 (-2775 5075)(-2775 5125);
WIRE 17 -1 (-2775 5125)(-2775 5175);
WIRE 17 -1 (-2775 5175)(-2775 5225);
WIRE 17 -1 (-2775 5225)(-2775 5275);
WIRE 17 -1 (-2775 5275)(-2775 5325);
WIRE 17 -1 (-2775 5325)(-2775 5375);
WIRE 17 -1 (-3600 5375)(-2775 5375);
FORCEPROP 2 LAST SIG_NAME M_F_CPU1_SA_CA<6:0>
J 0
(-3510 5385);
DISPLAY 0.680851 (-3510 5385);
PAINT WHITE (-3510 5385);
WIRE 17 -1 (-2775 4675)(-2775 4725);
WIRE 17 -1 (-2775 4725)(-2775 4775);
WIRE 17 -1 (-2775 4775)(-2775 4825);
WIRE 17 -1 (-2775 4825)(-2775 4875);
WIRE 17 -1 (-2775 4875)(-2775 4925);
WIRE 17 -1 (-2775 4925)(-2775 4975);
WIRE 17 -1 (-3600 4975)(-2775 4975);
FORCEPROP 2 LAST SIG_NAME M_F_CPU1_SB_CA<6:0>
J 0
(-3510 4985);
DISPLAY 0.680851 (-3510 4985);
PAINT WHITE (-3510 4985);
WIRE 17 -1 (-2775 3625)(-2775 3675);
WIRE 17 -1 (-2775 3425)(-2775 3475);
WIRE 17 -1 (-2775 3375)(-2775 3425);
WIRE 17 -1 (-2775 3475)(-2775 3525);
WIRE 17 -1 (-3600 3525)(-2775 3525);
FORCEPROP 2 LAST SIG_NAME M_F_CPU1_SB_CB<7:0>
J 0
(-3510 3535);
DISPLAY 0.680851 (-3510 3535);
PAINT WHITE (-3510 3535);
WIRE 17 -1 (-2775 3325)(-2775 3375);
WIRE 17 -1 (-2775 3275)(-2775 3325);
WIRE 17 -1 (-2775 3225)(-2775 3275);
WIRE 17 -1 (-2775 3175)(-2775 3225);
WIRE 17 -1 (-1025 5325)(-1025 5375);
WIRE 17 -1 (-1025 5275)(-1025 5325);
WIRE 17 -1 (-1025 5225)(-1025 5275);
WIRE 17 -1 (-1025 5175)(-1025 5225);
WIRE 17 -1 (-1025 5125)(-1025 5175);
WIRE 17 -1 (-1025 5075)(-1025 5125);
WIRE 17 -1 (-1025 5025)(-1025 5075);
WIRE 17 -1 (-1025 4975)(-1025 5025);
WIRE 17 -1 (-1025 4925)(-1025 4975);
WIRE 17 -1 (-1025 4875)(-1025 4925);
WIRE 17 -1 (-1025 4825)(-1025 4875);
WIRE 17 -1 (-1025 4775)(-1025 4825);
WIRE 17 -1 (-1025 4725)(-1025 4775);
WIRE 17 -1 (-1025 4675)(-1025 4725);
WIRE 17 -1 (-1025 4625)(-1025 4675);
WIRE 17 -1 (-1025 4575)(-1025 4625);
WIRE 17 -1 (-1025 4525)(-1025 4575);
WIRE 17 -1 (-1025 4475)(-1025 4525);
WIRE 17 -1 (-1025 4425)(-1025 4475);
WIRE 17 -1 (-1025 4375)(-1025 4425);
WIRE 17 -1 (-1025 4325)(-1025 4375);
WIRE 17 -1 (-1025 4275)(-1025 4325);
WIRE 17 -1 (-1025 4225)(-1025 4275);
WIRE 17 -1 (-1025 4175)(-1025 4225);
WIRE 17 -1 (-1025 4125)(-1025 4175);
WIRE 17 -1 (-1025 4075)(-1025 4125);
WIRE 17 -1 (-1025 4025)(-1025 4075);
WIRE 17 -1 (-1025 3975)(-1025 4025);
WIRE 17 -1 (-1025 3925)(-1025 3975);
WIRE 17 -1 (-1025 3875)(-1025 3925);
WIRE 17 -1 (-1025 3825)(-1025 3875);
WIRE 17 -1 (-1025 3725)(-300 3725);
FORCEPROP 2 LAST SIG_NAME M_F_CPU1_SB_DQ<31:0>
J 0
(-960 3735);
DISPLAY 0.680851 (-960 3735);
PAINT WHITE (-960 3735);
WIRE 17 -1 (-1025 3675)(-1025 3725);
WIRE 17 -1 (-1025 3625)(-1025 3675);
WIRE 17 -1 (-1025 3575)(-1025 3625);
WIRE 17 -1 (-1025 3525)(-1025 3575);
WIRE 17 -1 (-1025 3475)(-1025 3525);
WIRE 17 -1 (-1025 3425)(-1025 3475);
WIRE 17 -1 (-1025 3375)(-1025 3425);
WIRE 17 -1 (-1025 3325)(-1025 3375);
WIRE 17 -1 (-1025 3275)(-1025 3325);
WIRE 17 -1 (-1025 3225)(-1025 3275);
WIRE 17 -1 (-1025 3175)(-1025 3225);
WIRE 17 -1 (-1025 3125)(-1025 3175);
WIRE 17 -1 (-1025 3075)(-1025 3125);
WIRE 17 -1 (-1025 3025)(-1025 3075);
WIRE 17 -1 (-1025 2975)(-1025 3025);
WIRE 17 -1 (-1025 2925)(-1025 2975);
WIRE 17 -1 (-1025 2875)(-1025 2925);
WIRE 17 -1 (-1025 2825)(-1025 2875);
WIRE 17 -1 (-1025 2775)(-1025 2825);
WIRE 17 -1 (-1025 2725)(-1025 2775);
WIRE 17 -1 (-1025 2675)(-1025 2725);
WIRE 17 -1 (-1025 2625)(-1025 2675);
WIRE 17 -1 (-1025 2575)(-1025 2625);
WIRE 17 -1 (-1025 2525)(-1025 2575);
WIRE 17 -1 (-1025 2475)(-1025 2525);
WIRE 17 -1 (-1025 2425)(-1025 2475);
WIRE 17 -1 (-1025 2375)(-1025 2425);
WIRE 17 -1 (-1025 2325)(-1025 2375);
WIRE 17 -1 (-1025 2275)(-1025 2325);
WIRE 17 -1 (-1025 2225)(-1025 2275);
WIRE 17 -1 (-1025 2175)(-1025 2225);
WIRE 17 -1 (1725 3525)(1725 3625);
WIRE 17 -1 (1725 3425)(1725 3525);
WIRE 17 -1 (1725 3625)(1725 3725);
WIRE 17 -1 (1725 3825)(1725 3725);
WIRE 17 -1 (1725 3825)(1725 3925);
WIRE 17 -1 (1725 3925)(1725 4025);
WIRE 17 -1 (1725 4025)(1725 4125);
WIRE 17 -1 (1725 4125)(1725 4225);
WIRE 17 -1 (1725 4225)(1725 4325);
WIRE 17 -1 (1725 4325)(2750 4325);
FORCEPROP 2 LAST SIG_NAME M_F_CPU1_SB_DQS_DP<9:0>
J 0
(1965 4335);
DISPLAY 0.680851 (1965 4335);
PAINT WHITE (1965 4335);
WIRE 17 -1 (1725 4575)(1725 4675);
WIRE 17 -1 (1725 4475)(1725 4575);
WIRE 17 -1 (1725 4675)(1725 4775);
WIRE 17 -1 (1725 4875)(1725 4775);
WIRE 17 -1 (1725 4875)(1725 4975);
WIRE 17 -1 (1725 4975)(1725 5075);
WIRE 17 -1 (1725 5075)(1725 5175);
WIRE 17 -1 (1725 5175)(1725 5275);
WIRE 17 -1 (1725 5275)(1725 5375);
WIRE 17 -1 (1725 5375)(2750 5375);
FORCEPROP 2 LAST SIG_NAME M_F_CPU1_SA_DQS_DP<9:0>
J 0
(1965 5385);
DISPLAY 0.680851 (1965 5385);
PAINT WHITE (1965 5385);
WIRE 17 -1 (1900 3475)(1900 3575);
WIRE 17 -1 (1900 3375)(1900 3475);
WIRE 17 -1 (1900 3575)(1900 3675);
WIRE 17 -1 (1900 3775)(1900 3675);
WIRE 17 -1 (1900 3775)(1900 3875);
WIRE 17 -1 (1900 3875)(1900 3975);
WIRE 17 -1 (1900 3975)(1900 4075);
WIRE 17 -1 (1900 4075)(1900 4175);
WIRE 17 -1 (1900 4175)(1900 4275);
WIRE 17 -1 (1900 4275)(2750 4275);
FORCEPROP 2 LAST SIG_NAME M_F_CPU1_SB_DQS_DN<9:0>
J 0
(1965 4285);
DISPLAY 0.680851 (1965 4285);
PAINT WHITE (1965 4285);
WIRE 17 -1 (1900 4625)(1900 4725);
WIRE 17 -1 (1900 4525)(1900 4625);
WIRE 17 -1 (1900 4825)(1900 4725);
WIRE 17 -1 (1900 4825)(1900 4925);
WIRE 17 -1 (1900 4425)(1900 4525);
WIRE 17 -1 (1900 4925)(1900 5025);
WIRE 17 -1 (1900 5025)(1900 5125);
WIRE 17 -1 (1900 5125)(1900 5225);
WIRE 17 -1 (1900 5225)(1900 5325);
WIRE 17 -1 (1900 5325)(2750 5325);
FORCEPROP 2 LAST SIG_NAME M_F_CPU1_SA_DQS_DN<9:0>
J 0
(1965 5335);
DISPLAY 0.680851 (1965 5335);
PAINT WHITE (1965 5335);
WIRE 16 -1 (650 1575)(650 1750);
WIRE 16 -1 (1650 1750)(1650 1700);
WIRE 16 -1 (3350 5850)(3350 5350);
WIRE 16 -1 (-3550 3175)(-3550 2900);
WIRE 16 -1 (650 1375)(650 1150);
WIRE 16 -1 (2275 1150)(2275 1225);
WIRE 16 -1 (3350 1700)(3350 2100);
WIRE 16 -1 (5050 2000)(5050 1700);
WIRE 16 -1 (5050 2050)(5050 2000);
WIRE 16 -1 (4800 2000)(5050 2000);
WIRE 16 -1 (-2500 1025)(-2500 1100);
WIRE 16 -1 (-2500 2800)(-3475 2800);
FORCEPROP 2 LAST SIG_NAME I3C_SPD_DDREFGH_CPU1_LVC1_SDA
J 0
(-3485 2810);
DISPLAY 0.680851 (-3485 2810);
PAINT WHITE (-3485 2810);
WIRE 16 -1 (-4000 2675)(-3800 2675);
WIRE 16 -1 (-4000 2675)(-4000 2750);
WIRE 16 -1 (-2500 2750)(-4000 2750);
FORCEPROP 2 LAST SIG_NAME I3C_SPD_DDREFGH_CPU1_LVC1_SCL_R3
J 0
(-3560 2760);
DISPLAY 0.680851 (-3560 2760);
PAINT WHITE (-3560 2760);
WIRE 16 -1 (-2500 2850)(-3475 2850);
FORCEPROP 2 LAST SIG_NAME PD_CHF_CPU1_DIMM1_SAA
J 0
(-3485 2860);
DISPLAY 0.680851 (-3485 2860);
PAINT WHITE (-3485 2860);
WIRE 16 -1 (-3550 2900)(-2500 2900);
WIRE 16 -1 (-2875 3050)(-2500 3050);
WIRE 16 -1 (-2875 3100)(-3600 3100);
FORCEPROP 2 LAST SIG_NAME RST_M_EF_CPU1_FPGA_N
J 0
(-3512 3109);
DISPLAY 0.680851 (-3512 3109);
PAINT WHITE (-3512 3109);
WIRE 16 -1 (-2875 3100)(-2875 3050);
WIRE 16 -1 (-2500 3000)(-3600 3000);
FORCEPROP 2 LAST SIG_NAME M_F_CPU1_ALERT_N
J 0
(-3512 3009);
DISPLAY 0.680851 (-3512 3009);
PAINT WHITE (-3512 3009);
WIRE 16 -1 (-2375 2600)(-2425 2600);
WIRE 16 -1 (-2375 2675)(-2375 2600);
WIRE 16 -1 (-3600 2675)(-2375 2675);
FORCEPROP 2 LAST SIG_NAME I3C_SPD_DDREFGH_CPU1_LVC1_SCL
J 0
(-3410 2685);
DISPLAY 0.680851 (-3410 2685);
PAINT WHITE (-3410 2685);
WIRE 16 -1 (-2500 2500)(-3600 2500);
FORCEPROP 2 LAST SIG_NAME PWRGD_CHF_CPU1_DIMM1
J 0
(-3512 2509);
DISPLAY 0.680851 (-3512 2509);
PAINT WHITE (-3512 2509);
WIRE 16 -1 (-2500 2400)(-3600 2400);
FORCEPROP 2 LAST SIG_NAME TP_CHF_CPU1_DIMM1_FRU_6
J 0
(-3512 2409);
DISPLAY 0.680851 (-3512 2409);
PAINT WHITE (-3512 2409);
WIRE 16 -1 (1525 4200)(1625 4200);
WIRE 16 -1 (1525 4150)(1800 4150);
WIRE 16 -1 (1525 5300)(1800 5300);
WIRE 16 -1 (1525 5200)(1800 5200);
WIRE 16 -1 (1525 5100)(1800 5100);
WIRE 16 -1 (1525 5000)(1800 5000);
WIRE 16 -1 (1525 4900)(1800 4900);
WIRE 16 -1 (1525 4800)(1800 4800);
WIRE 16 -1 (1525 4700)(1800 4700);
WIRE 16 -1 (1525 4400)(1800 4400);
WIRE 16 -1 (1525 4500)(1800 4500);
WIRE 16 -1 (1525 4600)(1800 4600);
WIRE 16 -1 (1525 4250)(1800 4250);
WIRE 16 -1 (1525 4050)(1800 4050);
WIRE 16 -1 (1525 3950)(1800 3950);
WIRE 16 -1 (1525 3850)(1800 3850);
WIRE 16 -1 (1525 3750)(1800 3750);
WIRE 16 -1 (1525 3650)(1800 3650);
WIRE 16 -1 (1525 3350)(1800 3350);
WIRE 16 -1 (1525 3550)(1800 3550);
WIRE 16 -1 (1525 3450)(1800 3450);
WIRE 16 -1 (1525 5150)(1625 5150);
WIRE 16 -1 (1525 5250)(1625 5250);
WIRE 16 -1 (1525 5350)(1625 5350);
WIRE 16 -1 (1525 4950)(1625 4950);
WIRE 16 -1 (1525 5050)(1625 5050);
WIRE 16 -1 (1525 4850)(1625 4850);
WIRE 16 -1 (1525 4750)(1625 4750);
WIRE 16 -1 (1525 4650)(1625 4650);
WIRE 16 -1 (1525 4450)(1625 4450);
WIRE 16 -1 (1525 4550)(1625 4550);
WIRE 16 -1 (1525 4300)(1625 4300);
WIRE 16 -1 (1525 4100)(1625 4100);
WIRE 16 -1 (1525 4000)(1625 4000);
WIRE 16 -1 (1525 3900)(1625 3900);
WIRE 16 -1 (1525 3800)(1625 3800);
WIRE 16 -1 (1525 3700)(1625 3700);
WIRE 16 -1 (1525 3600)(1625 3600);
WIRE 16 -1 (1525 3400)(1625 3400);
WIRE 16 -1 (1525 3500)(1625 3500);
WIRE 16 -1 (-2675 3650)(-2500 3650);
WIRE 16 -1 (-2500 2150)(-3600 2150);
FORCEPROP 2 LAST SIG_NAME TP_CHF_CPU1_DIMM1_FRU_1
J 0
(-3512 2159);
DISPLAY 0.680851 (-3512 2159);
PAINT WHITE (-3512 2159);
WIRE 16 -1 (-2500 2250)(-3600 2250);
FORCEPROP 2 LAST SIG_NAME TP_CHF_CPU1_DIMM1_FRU_3
J 0
(-3512 2259);
DISPLAY 0.680851 (-3512 2259);
PAINT WHITE (-3512 2259);
WIRE 16 -1 (-2500 1950)(-3600 1950);
FORCEPROP 2 LAST SIG_NAME M_F_CPU1_SA_RSP<0>
J 0
(-3512 1959);
DISPLAY 0.680851 (-3512 1959);
PAINT WHITE (-3512 1959);
WIRE 16 -1 (-2500 2100)(-3600 2100);
FORCEPROP 2 LAST SIG_NAME TP_CHF_CPU1_DIMM1_FRU_0
J 0
(-3512 2109);
DISPLAY 0.680851 (-3512 2109);
PAINT WHITE (-3512 2109);
WIRE 16 -1 (-2500 2350)(-3600 2350);
FORCEPROP 2 LAST SIG_NAME TP_CHF_CPU1_DIMM1_FRU_5
J 0
(-3512 2359);
DISPLAY 0.680851 (-3512 2359);
PAINT WHITE (-3512 2359);
WIRE 16 -1 (-2675 3500)(-2500 3500);
WIRE 16 -1 (3600 5350)(3350 5350);
WIRE 16 -1 (3350 5350)(3350 5300);
WIRE 16 -1 (3350 5300)(3600 5300);
WIRE 16 -1 (3350 5300)(3350 5250);
WIRE 16 -1 (3600 5250)(3350 5250);
WIRE 16 -1 (-1300 4450)(-1125 4450);
WIRE 16 -1 (3350 2100)(3600 2100);
WIRE 16 -1 (3350 2100)(3350 2150);
WIRE 16 -1 (3350 2150)(3600 2150);
WIRE 16 -1 (3350 2150)(3350 2200);
WIRE 16 -1 (3350 2200)(3600 2200);
WIRE 16 -1 (3350 2200)(3350 2250);
WIRE 16 -1 (3350 2250)(3600 2250);
WIRE 16 -1 (3350 2250)(3350 2300);
WIRE 16 -1 (3350 2300)(3600 2300);
WIRE 16 -1 (3350 2300)(3350 2350);
WIRE 16 -1 (3350 2350)(3600 2350);
WIRE 16 -1 (3350 2350)(3350 2400);
WIRE 16 -1 (3350 2400)(3600 2400);
WIRE 16 -1 (3350 2400)(3350 2450);
WIRE 16 -1 (3350 2450)(3600 2450);
WIRE 16 -1 (3350 2450)(3350 2500);
WIRE 16 -1 (3350 2500)(3600 2500);
WIRE 16 -1 (3350 2500)(3350 2550);
WIRE 16 -1 (3350 2550)(3600 2550);
WIRE 16 -1 (3350 2550)(3350 2600);
WIRE 16 -1 (3600 2600)(3350 2600);
WIRE 16 -1 (3350 2600)(3350 2650);
WIRE 16 -1 (3350 2650)(3600 2650);
WIRE 16 -1 (3350 2650)(3350 2700);
WIRE 16 -1 (3350 2700)(3600 2700);
WIRE 16 -1 (3350 2700)(3350 2750);
WIRE 16 -1 (3350 2750)(3600 2750);
WIRE 16 -1 (3350 2750)(3350 2800);
WIRE 16 -1 (3350 2800)(3600 2800);
WIRE 16 -1 (3350 2800)(3350 2850);
WIRE 16 -1 (3350 2850)(3600 2850);
WIRE 16 -1 (3350 2850)(3350 2900);
WIRE 16 -1 (3350 2900)(3600 2900);
WIRE 16 -1 (3350 2900)(3350 2950);
WIRE 16 -1 (3350 2950)(3600 2950);
WIRE 16 -1 (3350 2950)(3350 3000);
WIRE 16 -1 (3350 3000)(3600 3000);
WIRE 16 -1 (3350 3000)(3350 3050);
WIRE 16 -1 (3350 3050)(3600 3050);
WIRE 16 -1 (3350 3050)(3350 3100);
WIRE 16 -1 (3600 3100)(3350 3100);
WIRE 16 -1 (3350 3100)(3350 3150);
WIRE 16 -1 (3350 3150)(3600 3150);
WIRE 16 -1 (3350 3150)(3350 3200);
WIRE 16 -1 (3350 3200)(3600 3200);
WIRE 16 -1 (3350 3200)(3350 3250);
WIRE 16 -1 (3350 3250)(3600 3250);
WIRE 16 -1 (3350 3250)(3350 3300);
WIRE 16 -1 (3350 3300)(3600 3300);
WIRE 16 -1 (3350 3300)(3350 3350);
WIRE 16 -1 (3350 3350)(3600 3350);
WIRE 16 -1 (3350 3350)(3350 3400);
WIRE 16 -1 (3350 3400)(3600 3400);
WIRE 16 -1 (3350 3400)(3350 3450);
WIRE 16 -1 (3350 3450)(3600 3450);
WIRE 16 -1 (3350 3450)(3350 3500);
WIRE 16 -1 (3350 3500)(3600 3500);
WIRE 16 -1 (3350 3500)(3350 3550);
WIRE 16 -1 (3350 3550)(3600 3550);
WIRE 16 -1 (3350 3550)(3350 3600);
WIRE 16 -1 (3600 3600)(3350 3600);
WIRE 16 -1 (3350 3600)(3350 3650);
WIRE 16 -1 (3350 3650)(3600 3650);
WIRE 16 -1 (3350 3650)(3350 3700);
WIRE 16 -1 (3350 3700)(3600 3700);
WIRE 16 -1 (3350 3700)(3350 3750);
WIRE 16 -1 (3350 3750)(3600 3750);
WIRE 16 -1 (3350 3750)(3350 3800);
WIRE 16 -1 (3350 3800)(3600 3800);
WIRE 16 -1 (3350 3800)(3350 3850);
WIRE 16 -1 (3350 3850)(3600 3850);
WIRE 16 -1 (3350 3850)(3350 3900);
WIRE 16 -1 (3350 3900)(3600 3900);
WIRE 16 -1 (3350 3900)(3350 3950);
WIRE 16 -1 (3350 3950)(3600 3950);
WIRE 16 -1 (3350 3950)(3350 4000);
WIRE 16 -1 (3350 4000)(3600 4000);
WIRE 16 -1 (3350 4000)(3350 4050);
WIRE 16 -1 (3350 4050)(3600 4050);
WIRE 16 -1 (3350 4050)(3350 4100);
WIRE 16 -1 (3600 4100)(3350 4100);
WIRE 16 -1 (3350 4100)(3350 4150);
WIRE 16 -1 (3350 4150)(3600 4150);
WIRE 16 -1 (3350 4150)(3350 4200);
WIRE 16 -1 (3350 4200)(3600 4200);
WIRE 16 -1 (3350 4200)(3350 4250);
WIRE 16 -1 (3350 4250)(3600 4250);
WIRE 16 -1 (3350 4250)(3350 4300);
WIRE 16 -1 (3350 4300)(3600 4300);
WIRE 16 -1 (3350 4300)(3350 4350);
WIRE 16 -1 (3350 4350)(3600 4350);
WIRE 16 -1 (3350 4350)(3350 4400);
WIRE 16 -1 (3350 4400)(3600 4400);
WIRE 16 -1 (3350 4400)(3350 4450);
WIRE 16 -1 (3350 4450)(3600 4450);
WIRE 16 -1 (3350 4450)(3350 4500);
WIRE 16 -1 (3350 4500)(3600 4500);
WIRE 16 -1 (3350 4500)(3350 4550);
WIRE 16 -1 (3350 4550)(3600 4550);
WIRE 16 -1 (3350 4550)(3350 4600);
WIRE 16 -1 (3600 4600)(3350 4600);
WIRE 16 -1 (3350 4600)(3350 4650);
WIRE 16 -1 (3350 4650)(3600 4650);
WIRE 16 -1 (3350 4650)(3350 4700);
WIRE 16 -1 (3350 4700)(3600 4700);
WIRE 16 -1 (3350 4700)(3350 4750);
WIRE 16 -1 (3350 4750)(3600 4750);
WIRE 16 -1 (3350 4750)(3350 4800);
WIRE 16 -1 (3350 4800)(3600 4800);
WIRE 16 -1 (3350 4800)(3350 4850);
WIRE 16 -1 (3350 4850)(3600 4850);
WIRE 16 -1 (3350 4850)(3350 4900);
WIRE 16 -1 (3350 4900)(3600 4900);
WIRE 16 -1 (3350 4900)(3350 4950);
WIRE 16 -1 (3350 4950)(3600 4950);
WIRE 16 -1 (3350 4950)(3350 5000);
WIRE 16 -1 (3350 5000)(3600 5000);
WIRE 16 -1 (3350 5000)(3350 5050);
WIRE 16 -1 (3350 5050)(3600 5050);
WIRE 16 -1 (3350 5050)(3350 5100);
WIRE 16 -1 (3600 5100)(3350 5100);
WIRE 16 -1 (3350 5100)(3350 5150);
WIRE 16 -1 (3350 5150)(3600 5150);
WIRE 16 -1 (3350 5150)(3350 5200);
WIRE 16 -1 (3600 5200)(3350 5200);
WIRE 16 -1 (-1300 5200)(-1125 5200);
WIRE 16 -1 (-1300 4800)(-1125 4800);
WIRE 16 -1 (-1300 4750)(-1125 4750);
WIRE 16 -1 (4800 5350)(5050 5350);
WIRE 16 -1 (4800 5300)(5050 5300);
WIRE 16 -1 (5050 5350)(5050 5300);
WIRE 16 -1 (4800 5250)(5050 5250);
WIRE 16 -1 (5050 5300)(5050 5250);
WIRE 16 -1 (4800 5200)(5050 5200);
WIRE 16 -1 (5050 5250)(5050 5200);
WIRE 16 -1 (4800 5150)(5050 5150);
WIRE 16 -1 (5050 5200)(5050 5150);
WIRE 16 -1 (4800 5100)(5050 5100);
WIRE 16 -1 (5050 5150)(5050 5100);
WIRE 16 -1 (4800 5050)(5050 5050);
WIRE 16 -1 (5050 5100)(5050 5050);
WIRE 16 -1 (4800 5000)(5050 5000);
WIRE 16 -1 (5050 5050)(5050 5000);
WIRE 16 -1 (4800 4950)(5050 4950);
WIRE 16 -1 (5050 5000)(5050 4950);
WIRE 16 -1 (4800 4900)(5050 4900);
WIRE 16 -1 (5050 4950)(5050 4900);
WIRE 16 -1 (4800 4850)(5050 4850);
WIRE 16 -1 (5050 4900)(5050 4850);
WIRE 16 -1 (4800 4800)(5050 4800);
WIRE 16 -1 (5050 4850)(5050 4800);
WIRE 16 -1 (4800 4750)(5050 4750);
WIRE 16 -1 (5050 4800)(5050 4750);
WIRE 16 -1 (4800 4700)(5050 4700);
WIRE 16 -1 (5050 4750)(5050 4700);
WIRE 16 -1 (4800 4650)(5050 4650);
WIRE 16 -1 (5050 4700)(5050 4650);
WIRE 16 -1 (4800 4600)(5050 4600);
WIRE 16 -1 (5050 4600)(5050 4650);
WIRE 16 -1 (4800 4550)(5050 4550);
WIRE 16 -1 (5050 4600)(5050 4550);
WIRE 16 -1 (5050 4500)(4800 4500);
WIRE 16 -1 (5050 4550)(5050 4500);
WIRE 16 -1 (5050 4450)(4800 4450);
WIRE 16 -1 (5050 4500)(5050 4450);
WIRE 16 -1 (4800 4400)(5050 4400);
WIRE 16 -1 (5050 4450)(5050 4400);
WIRE 16 -1 (4800 4350)(5050 4350);
WIRE 16 -1 (5050 4400)(5050 4350);
WIRE 16 -1 (4800 4300)(5050 4300);
WIRE 16 -1 (5050 4350)(5050 4300);
WIRE 16 -1 (4800 4250)(5050 4250);
WIRE 16 -1 (5050 4300)(5050 4250);
WIRE 16 -1 (4800 4200)(5050 4200);
WIRE 16 -1 (5050 4250)(5050 4200);
WIRE 16 -1 (4800 4150)(5050 4150);
WIRE 16 -1 (5050 4200)(5050 4150);
WIRE 16 -1 (4800 4100)(5050 4100);
WIRE 16 -1 (5050 4100)(5050 4150);
WIRE 16 -1 (4800 4050)(5050 4050);
WIRE 16 -1 (5050 4100)(5050 4050);
WIRE 16 -1 (5050 4000)(4800 4000);
WIRE 16 -1 (5050 4050)(5050 4000);
WIRE 16 -1 (5050 3950)(4800 3950);
WIRE 16 -1 (5050 4000)(5050 3950);
WIRE 16 -1 (4800 3900)(5050 3900);
WIRE 16 -1 (5050 3950)(5050 3900);
WIRE 16 -1 (4800 3850)(5050 3850);
WIRE 16 -1 (5050 3900)(5050 3850);
WIRE 16 -1 (4800 3800)(5050 3800);
WIRE 16 -1 (5050 3850)(5050 3800);
WIRE 16 -1 (4800 3750)(5050 3750);
WIRE 16 -1 (5050 3800)(5050 3750);
WIRE 16 -1 (4800 3700)(5050 3700);
WIRE 16 -1 (5050 3750)(5050 3700);
WIRE 16 -1 (4800 3650)(5050 3650);
WIRE 16 -1 (5050 3700)(5050 3650);
WIRE 16 -1 (4800 3600)(5050 3600);
WIRE 16 -1 (5050 3600)(5050 3650);
WIRE 16 -1 (4800 3550)(5050 3550);
WIRE 16 -1 (5050 3600)(5050 3550);
WIRE 16 -1 (5050 3500)(4800 3500);
WIRE 16 -1 (5050 3550)(5050 3500);
WIRE 16 -1 (5050 3450)(4800 3450);
WIRE 16 -1 (5050 3500)(5050 3450);
WIRE 16 -1 (4800 3400)(5050 3400);
WIRE 16 -1 (5050 3450)(5050 3400);
WIRE 16 -1 (4800 3350)(5050 3350);
WIRE 16 -1 (5050 3400)(5050 3350);
WIRE 16 -1 (4800 3300)(5050 3300);
WIRE 16 -1 (5050 3350)(5050 3300);
WIRE 16 -1 (4800 3250)(5050 3250);
WIRE 16 -1 (5050 3300)(5050 3250);
WIRE 16 -1 (4800 3200)(5050 3200);
WIRE 16 -1 (5050 3250)(5050 3200);
WIRE 16 -1 (4800 3150)(5050 3150);
WIRE 16 -1 (5050 3200)(5050 3150);
WIRE 16 -1 (4800 3100)(5050 3100);
WIRE 16 -1 (5050 3100)(5050 3150);
WIRE 16 -1 (4800 3050)(5050 3050);
WIRE 16 -1 (5050 3100)(5050 3050);
WIRE 16 -1 (5050 3000)(4800 3000);
WIRE 16 -1 (5050 3050)(5050 3000);
WIRE 16 -1 (5050 2950)(4800 2950);
WIRE 16 -1 (5050 3000)(5050 2950);
WIRE 16 -1 (5050 2900)(4800 2900);
WIRE 16 -1 (5050 2950)(5050 2900);
WIRE 16 -1 (5050 2850)(4800 2850);
WIRE 16 -1 (5050 2900)(5050 2850);
WIRE 16 -1 (4800 2800)(5050 2800);
WIRE 16 -1 (5050 2800)(5050 2850);
WIRE 16 -1 (5050 2750)(4800 2750);
WIRE 16 -1 (5050 2750)(5050 2800);
WIRE 16 -1 (5050 2700)(4800 2700);
WIRE 16 -1 (5050 2750)(5050 2700);
WIRE 16 -1 (5050 2650)(4800 2650);
WIRE 16 -1 (5050 2700)(5050 2650);
WIRE 16 -1 (4800 2600)(5050 2600);
WIRE 16 -1 (5050 2650)(5050 2600);
WIRE 16 -1 (4800 2550)(5050 2550);
WIRE 16 -1 (5050 2600)(5050 2550);
WIRE 16 -1 (4800 2500)(5050 2500);
WIRE 16 -1 (5050 2550)(5050 2500);
WIRE 16 -1 (4800 2450)(5050 2450);
WIRE 16 -1 (5050 2500)(5050 2450);
WIRE 16 -1 (4800 2400)(5050 2400);
WIRE 16 -1 (5050 2450)(5050 2400);
WIRE 16 -1 (4800 2350)(5050 2350);
WIRE 16 -1 (5050 2400)(5050 2350);
WIRE 16 -1 (4800 2300)(5050 2300);
WIRE 16 -1 (5050 2350)(5050 2300);
WIRE 16 -1 (4800 2250)(5050 2250);
WIRE 16 -1 (5050 2250)(5050 2300);
WIRE 16 -1 (4800 2200)(5050 2200);
WIRE 16 -1 (5050 2250)(5050 2200);
WIRE 16 -1 (4800 2100)(5050 2100);
WIRE 16 -1 (5050 2200)(5050 2100);
WIRE 16 -1 (5050 2100)(5050 2050);
WIRE 16 -1 (4800 2050)(5050 2050);
WIRE 16 -1 (-1300 3000)(-1125 3000);
WIRE 16 -1 (-2500 2200)(-3600 2200);
FORCEPROP 2 LAST SIG_NAME TP_CHF_CPU1_DIMM1_FRU_2
J 0
(-3512 2209);
DISPLAY 0.680851 (-3512 2209);
PAINT WHITE (-3512 2209);
WIRE 16 -1 (-2500 2300)(-3600 2300);
FORCEPROP 2 LAST SIG_NAME TP_CHF_CPU1_DIMM1_FRU_4
J 0
(-3512 2309);
DISPLAY 0.680851 (-3512 2309);
PAINT WHITE (-3512 2309);
WIRE 16 -1 (-2500 4500)(-3600 4500);
FORCEPROP 2 LAST SIG_NAME M_F_CPU1_SB_PAR
J 0
(-3512 4509);
DISPLAY 0.680851 (-3512 4509);
PAINT WHITE (-3512 4509);
WIRE 16 -1 (-2500 4550)(-3600 4550);
FORCEPROP 2 LAST SIG_NAME M_F_CPU1_SA_PAR
J 0
(-3512 4559);
DISPLAY 0.680851 (-3512 4559);
PAINT WHITE (-3512 4559);
WIRE 16 -1 (-2500 1900)(-3600 1900);
FORCEPROP 2 LAST SIG_NAME M_F_CPU1_SB_RSP<0>
J 0
(-3512 1909);
DISPLAY 0.680851 (-3512 1909);
PAINT WHITE (-3512 1909);
WIRE 16 -1 (-1300 2150)(-1125 2150);
WIRE 16 -1 (-1300 2200)(-1125 2200);
WIRE 16 -1 (-1300 2250)(-1125 2250);
WIRE 16 -1 (-1300 2300)(-1125 2300);
WIRE 16 -1 (-1300 2350)(-1125 2350);
WIRE 16 -1 (-1300 2400)(-1125 2400);
WIRE 16 -1 (-1300 2450)(-1125 2450);
WIRE 16 -1 (-1300 2500)(-1125 2500);
WIRE 16 -1 (-1300 2550)(-1125 2550);
WIRE 16 -1 (-1300 2600)(-1125 2600);
WIRE 16 -1 (-1300 2650)(-1125 2650);
WIRE 16 -1 (-1300 2700)(-1125 2700);
WIRE 16 -1 (-1300 2750)(-1125 2750);
WIRE 16 -1 (-1300 2800)(-1125 2800);
WIRE 16 -1 (-1300 2850)(-1125 2850);
WIRE 16 -1 (-1300 2900)(-1125 2900);
WIRE 16 -1 (-1300 2950)(-1125 2950);
WIRE 16 -1 (-1300 3050)(-1125 3050);
WIRE 16 -1 (-1300 3100)(-1125 3100);
WIRE 16 -1 (-1300 3150)(-1125 3150);
WIRE 16 -1 (-1300 3200)(-1125 3200);
WIRE 16 -1 (-1300 3250)(-1125 3250);
WIRE 16 -1 (-1300 3300)(-1125 3300);
WIRE 16 -1 (-1300 3350)(-1125 3350);
WIRE 16 -1 (-1300 3400)(-1125 3400);
WIRE 16 -1 (-1300 3450)(-1125 3450);
WIRE 16 -1 (-1300 3500)(-1125 3500);
WIRE 16 -1 (-1300 3550)(-1125 3550);
WIRE 16 -1 (-1300 3600)(-1125 3600);
WIRE 16 -1 (-1300 3650)(-1125 3650);
WIRE 16 -1 (-1300 3700)(-1125 3700);
WIRE 16 -1 (-1300 3800)(-1125 3800);
WIRE 16 -1 (-1300 3850)(-1125 3850);
WIRE 16 -1 (-1300 3900)(-1125 3900);
WIRE 16 -1 (-1300 3950)(-1125 3950);
WIRE 16 -1 (-1300 4000)(-1125 4000);
WIRE 16 -1 (-1300 4050)(-1125 4050);
WIRE 16 -1 (-1300 4100)(-1125 4100);
WIRE 16 -1 (-1300 4150)(-1125 4150);
WIRE 16 -1 (-1300 4200)(-1125 4200);
WIRE 16 -1 (-1300 4250)(-1125 4250);
WIRE 16 -1 (-1300 4300)(-1125 4300);
WIRE 16 -1 (-1300 4350)(-1125 4350);
WIRE 16 -1 (-1300 4400)(-1125 4400);
WIRE 16 -1 (-1300 4500)(-1125 4500);
WIRE 16 -1 (-1300 4550)(-1125 4550);
WIRE 16 -1 (-1300 4600)(-1125 4600);
WIRE 16 -1 (-1300 4650)(-1125 4650);
WIRE 16 -1 (-1300 4700)(-1125 4700);
WIRE 16 -1 (-1300 4850)(-1125 4850);
WIRE 16 -1 (-1300 4900)(-1125 4900);
WIRE 16 -1 (-1300 4950)(-1125 4950);
WIRE 16 -1 (-1300 5000)(-1125 5000);
WIRE 16 -1 (-1300 5050)(-1125 5050);
WIRE 16 -1 (-1300 5100)(-1125 5100);
WIRE 16 -1 (-1300 5150)(-1125 5150);
WIRE 16 -1 (-1300 5250)(-1125 5250);
WIRE 16 -1 (-1300 5300)(-1125 5300);
WIRE 16 -1 (-2500 4250)(-3600 4250);
FORCEPROP 2 LAST SIG_NAME M_F_CPU1_SB_CS_N<1>
J 0
(-3512 4259);
DISPLAY 0.680851 (-3512 4259);
PAINT WHITE (-3512 4259);
WIRE 16 -1 (-2500 4400)(-3600 4400);
FORCEPROP 2 LAST SIG_NAME M_F_CPU1_SA_CS_N<1>
J 0
(-3512 4409);
DISPLAY 0.680851 (-3512 4409);
PAINT WHITE (-3512 4409);
WIRE 16 -1 (-2500 4200)(-3600 4200);
FORCEPROP 2 LAST SIG_NAME M_F_CPU1_SB_CS_N<0>
J 0
(-3512 4209);
DISPLAY 0.680851 (-3512 4209);
PAINT WHITE (-3512 4209);
WIRE 16 -1 (-2500 4350)(-3600 4350);
FORCEPROP 2 LAST SIG_NAME M_F_CPU1_SA_CS_N<0>
J 0
(-3512 4359);
DISPLAY 0.680851 (-3512 4359);
PAINT WHITE (-3512 4359);
WIRE 16 -1 (-2500 4100)(-3600 4100);
FORCEPROP 2 LAST SIG_NAME M_F_CPU1_CLK_DP<0>
J 0
(-3512 4109);
DISPLAY 0.680851 (-3512 4109);
PAINT WHITE (-3512 4109);
WIRE 16 -1 (-2500 4050)(-3600 4050);
FORCEPROP 2 LAST SIG_NAME M_F_CPU1_CLK_DN<0>
J 0
(-3512 4059);
DISPLAY 0.680851 (-3512 4059);
PAINT WHITE (-3512 4059);
WIRE 16 -1 (-2675 3150)(-2500 3150);
WIRE 16 -1 (-2675 3200)(-2500 3200);
WIRE 16 -1 (-2675 3250)(-2500 3250);
WIRE 16 -1 (-2675 3300)(-2500 3300);
WIRE 16 -1 (-2675 3350)(-2500 3350);
WIRE 16 -1 (-2675 3400)(-2500 3400);
WIRE 16 -1 (-2675 3450)(-2500 3450);
WIRE 16 -1 (-2675 3600)(-2500 3600);
WIRE 16 -1 (-2675 3700)(-2500 3700);
WIRE 16 -1 (-2675 3750)(-2500 3750);
WIRE 16 -1 (-2675 3850)(-2500 3850);
WIRE 16 -1 (-2675 3900)(-2500 3900);
WIRE 16 -1 (-2675 4950)(-2500 4950);
WIRE 16 -1 (-2675 5350)(-2500 5350);
WIRE 16 -1 (-2675 4900)(-2500 4900);
WIRE 16 -1 (-2675 5300)(-2500 5300);
WIRE 16 -1 (-2675 4850)(-2500 4850);
WIRE 16 -1 (-2675 5250)(-2500 5250);
WIRE 16 -1 (-2675 4800)(-2500 4800);
WIRE 16 -1 (-2675 5200)(-2500 5200);
WIRE 16 -1 (-2675 4750)(-2500 4750);
WIRE 16 -1 (-2675 5150)(-2500 5150);
WIRE 16 -1 (-2675 4700)(-2500 4700);
WIRE 16 -1 (-2675 5100)(-2500 5100);
WIRE 16 -1 (-2675 4650)(-2500 4650);
WIRE 16 -1 (-2675 5050)(-2500 5050);
WIRE 16 -1 (-2675 3800)(-2500 3800);
WIRE 16 -1 (-2675 3950)(-2500 3950);
WIRE 16 -1 (-1300 5350)(-1125 5350);
WIRE 16 -1 (-2500 1400)(-3600 1400);
FORCEPROP 2 LAST SIG_NAME PD_CHF_CPU1_DIMM1_SAA
J 0
(-3512 1409);
DISPLAY 0.680851 (-3512 1409);
PAINT WHITE (-3512 1409);
WIRE 16 -1 (-2500 1300)(-2500 1400);
WIRE 16 -1 (1650 1700)(1650 1575);
WIRE 16 -1 (2275 1700)(1650 1700);
WIRE 16 -1 (2275 1575)(2275 1700);
WIRE 16 -1 (1650 1225)(1650 1375);
WIRE 16 -1 (2275 1225)(1650 1225);
WIRE 16 -1 (2275 1225)(2275 1375);
WIRE 16 3135 (2900 1975)(300 1975);
WIRE 16 3135 (2900 675)(2900 1975);
WIRE 16 3135 (300 1975)(300 675);
WIRE 16 3135 (300 675)(2900 675);
DOT 1 (3350 4800);
DOT 1 (3350 4850);
DOT 1 (3350 3100);
DOT 1 (3350 4200);
DOT 1 (1650 1700);
DOT 1 (2275 1225);
DOT 1 (3350 2100);
DOT 1 (3350 2150);
DOT 1 (3350 2200);
DOT 1 (3350 2250);
DOT 1 (3350 2300);
DOT 1 (3350 2350);
DOT 1 (3350 2400);
DOT 1 (3350 2450);
DOT 1 (3350 2500);
DOT 1 (3350 2550);
DOT 1 (3350 2600);
DOT 1 (3350 2650);
DOT 1 (3350 2700);
DOT 1 (3350 2750);
DOT 1 (3350 2800);
DOT 1 (3350 2850);
DOT 1 (3350 2900);
DOT 1 (3350 2950);
DOT 1 (3350 3000);
DOT 1 (3350 3050);
DOT 1 (3350 3200);
DOT 1 (3350 3150);
DOT 1 (3350 3250);
DOT 1 (3350 3300);
DOT 1 (3350 3350);
DOT 1 (3350 3400);
DOT 1 (3350 3450);
DOT 1 (3350 3500);
DOT 1 (3350 3550);
DOT 1 (3350 3600);
DOT 1 (3350 3650);
DOT 1 (3350 3700);
DOT 1 (3350 3750);
DOT 1 (3350 3800);
DOT 1 (3350 3850);
DOT 1 (3350 3900);
DOT 1 (3350 3950);
DOT 1 (3350 4000);
DOT 1 (3350 4050);
DOT 1 (3350 4100);
DOT 1 (3350 4150);
DOT 1 (3350 4250);
DOT 1 (3350 4300);
DOT 1 (3350 4350);
DOT 1 (3350 4400);
DOT 1 (3350 4450);
DOT 1 (3350 4500);
DOT 1 (3350 4550);
DOT 1 (3350 4600);
DOT 1 (3350 4650);
DOT 1 (3350 4700);
DOT 1 (3350 4750);
DOT 1 (3350 4900);
DOT 1 (3350 4950);
DOT 1 (3350 5000);
DOT 1 (3350 5050);
DOT 1 (3350 5100);
DOT 1 (3350 5150);
DOT 1 (3350 5300);
DOT 1 (3350 5350);
DOT 1 (5050 2250);
DOT 1 (5050 2300);
DOT 1 (5050 2200);
DOT 1 (5050 2350);
DOT 1 (5050 2400);
DOT 1 (5050 2500);
DOT 1 (5050 2550);
DOT 1 (5050 2450);
DOT 1 (5050 2650);
DOT 1 (5050 2600);
DOT 1 (5050 2700);
DOT 1 (5050 2800);
DOT 1 (5050 2750);
DOT 1 (5050 2850);
DOT 1 (5050 2900);
DOT 1 (5050 2950);
DOT 1 (5050 3050);
DOT 1 (5050 3000);
DOT 1 (5050 3100);
DOT 1 (5050 3150);
DOT 1 (5050 3200);
DOT 1 (5050 3250);
DOT 1 (5050 3300);
DOT 1 (5050 3400);
DOT 1 (5050 3450);
DOT 1 (5050 3350);
DOT 1 (5050 3500);
DOT 1 (5050 3550);
DOT 1 (5050 3650);
DOT 1 (5050 3700);
DOT 1 (5050 3600);
DOT 1 (5050 3750);
DOT 1 (5050 3800);
DOT 1 (5050 3850);
DOT 1 (5050 3950);
DOT 1 (5050 3900);
DOT 1 (5050 4000);
DOT 1 (5050 4050);
DOT 1 (5050 4100);
DOT 1 (5050 4200);
DOT 1 (5050 4150);
DOT 1 (5050 4300);
DOT 1 (5050 4350);
DOT 1 (5050 4250);
DOT 1 (5050 4400);
DOT 1 (5050 4450);
DOT 1 (5050 4550);
DOT 1 (5050 4600);
DOT 1 (5050 4500);
DOT 1 (5050 4700);
DOT 1 (5050 4650);
DOT 1 (5050 4750);
DOT 1 (5050 4800);
DOT 1 (5050 4850);
DOT 1 (5050 4900);
DOT 1 (5050 4950);
DOT 1 (5050 5000);
DOT 1 (5050 5100);
DOT 1 (5050 5050);
DOT 1 (5050 5200);
DOT 1 (5050 5150);
DOT 1 (5050 5250);
DOT 1 (5050 5300);
DOT 1 (5050 2100);
DOT 1 (5050 2050);
DOT 1 (5050 2000);
FORCENOTE
20210728 MODIFY FOR GT
(-4050 6050) 0;
DISPLAY LEFT (-4050 6050);
DISPLAY 2.510638 (-4050 6050);
PAINT PINK (-4050 6050);
QUIT
